FILE_TYPE = MACRO_DRAWING;
SET COLOR_WIRE YELLOW;
SET COLOR_PROP ORANGE;
SET COLOR_DOT WHITE;
SET COLOR_ARC YELLOW;
SET COLOR_BODY GREEN;
SET COLOR_NOTE PURPLE;
SET PROP_DISPLAY VALUE;
SET PAGE_NUMBER P295;
FORCEADD OFFPAGE..2
(5825 725);
FORCEPROP 2 LAST $XR1 82 
J 0
(6134 725);
DISPLAY 0.638298 (6134 725);
PAINT MONO (6134 725);
FORCEPROP 2 LAST $XR0 358 
J 0
(6014 725);
DISPLAY 0.638298 (6014 725);
PAINT MONO (6014 725);
FORCEPROP 2 LAST CDS_LIB standard
J 0
(5825 725);
DISPLAY INVISIBLE (5825 725);
FORCEPROP 1 LAST OFFPAGE TRUE
J 0
(6150 600);
DISPLAY 0.872340 (6150 600);
DISPLAY INVISIBLE (6150 600);
FORCEPROP 1 LAST COMMENT_BODY TRUE
J 0
(5780 630);
DISPLAY 0.872340 (5780 630);
PAINT GREEN (5780 630);
DISPLAY INVISIBLE (5780 630);
FORCEPROP 2 LAST PATH I121
J 0
(6025 775);
DISPLAY 1.021277 (6025 775);
DISPLAY INVISIBLE (6025 775);
FORCEADD Q_RES..1
(4450 725);
FORCEPROP 1 LAST LOCATION R3752
J 0
(4275 725);
DISPLAY 0.510638 (4275 725);
FORCEPROP 0 LAST $SEC 1
J 0
(4750 775);
DISPLAY 0.680851 (4750 775);
PAINT MONO (4750 775);
DISPLAY INVISIBLE (4750 775);
FORCEPROP 0 LAST CDS_SEC 1
J 0
(4750 775);
DISPLAY 1.021277 (4750 775);
DISPLAY INVISIBLE (4750 775);
FORCEPROP 1 LASTPIN (4350 725) $PN 1
J 0
(4362 737);
DISPLAY 0.787234 (4362 737);
PAINT MONO (4362 737);
FORCEPROP 1 LASTPIN (4550 725) $PN 2
J 0
(4512 737);
DISPLAY 0.787234 (4512 737);
PAINT MONO (4512 737);
FORCEPROP 1 LAST VALUE 0
J 2
(4600 725);
DISPLAY 0.574468 (4600 725);
FORCEPROP 1 LAST MATERIAL CHIP
J 0
(4625 725);
DISPLAY 0.574468 (4625 725);
FORCEPROP 1 LAST PACK_TYPE 0402LF
J 0
(4750 725);
DISPLAY 0.574468 (4750 725);
FORCEPROP 2 LAST CDS_LIB pure_quanta
J 0
(4450 725);
DISPLAY INVISIBLE (4450 725);
FORCEPROP 1 LAST TOLERANCE 5%
J 0
(4250 650);
DISPLAY 0.723404 (4250 650);
PAINT SKYBLUE (4250 650);
DISPLAY INVISIBLE (4250 650);
FORCEPROP 1 LAST WATTAGE 1/16W
J 2
(4525 650);
DISPLAY 0.723404 (4525 650);
PAINT SKYBLUE (4525 650);
DISPLAY INVISIBLE (4525 650);
FORCEPROP 1 LAST PATH I122
J 0
(4400 875);
DISPLAY 0.978723 (4400 875);
PAINT WHITE (4400 875);
DISPLAY INVISIBLE (4400 875);
FORCEPROP 1 LAST PART_NUMBER CS00002JB13
J 0
(4175 600);
DISPLAY 0.723404 (4175 600);
PAINT WHITE (4175 600);
DISPLAY INVISIBLE (4175 600);
FORCEADD UNIVERSAL_POWER..1
(2425 1475);
FORCEPROP 3 LASTPIN (2425 1425) SIG_NAME P3V3_AUX\g
J 0
(2435 1435);
DISPLAY 0.659574 (2435 1435);
PAINT MONO (2435 1435);
DISPLAY INVISIBLE (2435 1435);
FORCEPROP 1 LAST HDL_POWER P3V3_AUX
J 1
(2425 1525);
DISPLAY 0.872340 (2425 1525);
PAINT GREEN (2425 1525);
FORCEPROP 2 LAST CDS_LIB pure_quanta_power
J 0
(2425 1475);
DISPLAY INVISIBLE (2425 1475);
FORCEPROP 1 LAST PATH I123
J 0
(2475 1500);
DISPLAY 0.872340 (2475 1500);
PAINT AQUA (2475 1500);
DISPLAY INVISIBLE (2475 1500);
FORCEADD UNIVERSAL_GND..1
(2175 800);
FORCEPROP 3 LASTPIN (2175 850) SIG_NAME GND\g
J 0
(2185 860);
DISPLAY 0.659574 (2185 860);
PAINT MONO (2185 860);
DISPLAY INVISIBLE (2185 860);
FORCEPROP 2 LAST CDS_LIB pure_quanta_power
J 0
(2175 800);
DISPLAY INVISIBLE (2175 800);
FORCEPROP 1 LAST HDL_POWER GND
J 1
(2200 725);
DISPLAY 0.872340 (2200 725);
PAINT GREEN (2200 725);
DISPLAY INVISIBLE (2200 725);
FORCEPROP 1 LAST PATH I124
J 0
(2250 800);
DISPLAY 0.872340 (2250 800);
PAINT AQUA (2250 800);
DISPLAY INVISIBLE (2250 800);
FORCEADD Q_CAP..1
(2175 1075);
FORCEPROP 1 LAST LOCATION C2067
J 0
(2225 1175);
DISPLAY 0.978723 (2225 1175);
FORCEPROP 0 LAST $SEC 1
J 0
(2225 1225);
DISPLAY 0.680851 (2225 1225);
PAINT MONO (2225 1225);
DISPLAY INVISIBLE (2225 1225);
FORCEPROP 0 LAST CDS_SEC 1
J 0
(2225 1225);
DISPLAY 1.021277 (2225 1225);
DISPLAY INVISIBLE (2225 1225);
FORCEPROP 1 LASTPIN (2175 1175) $PN 1
J 0
(2185 1155);
DISPLAY 0.787234 (2185 1155);
PAINT MONO (2185 1155);
FORCEPROP 1 LASTPIN (2175 975) $PN 2
J 0
(2185 955);
DISPLAY 0.787234 (2185 955);
PAINT MONO (2185 955);
FORCEPROP 1 LAST VOLTAGE 25V
J 0
(2225 1075);
DISPLAY 0.638298 (2225 1075);
FORCEPROP 1 LAST VALUE 0.1UF
J 0
(2225 1125);
DISPLAY 0.638298 (2225 1125);
FORCEPROP 1 LAST TOLERANCE 10%
J 0
(2225 1025);
DISPLAY 0.638298 (2225 1025);
FORCEPROP 1 LAST MATERIAL X7R
J 0
(2225 975);
DISPLAY 0.638298 (2225 975);
FORCEPROP 1 LAST PACK_TYPE 0402
J 0
(2225 925);
DISPLAY 0.638298 (2225 925);
FORCEPROP 2 LAST CDS_LIB pure_quanta
J 0
(2175 1075);
DISPLAY INVISIBLE (2175 1075);
FORCEPROP 1 LAST PATH I125
J 0
(2225 1225);
DISPLAY 0.978723 (2225 1225);
PAINT WHITE (2225 1225);
DISPLAY INVISIBLE (2225 1225);
FORCEPROP 1 LAST PART_NUMBER CH4104K1B00
J 0
(2225 925);
DISPLAY 0.808511 (2225 925);
DISPLAY INVISIBLE (2225 925);
FORCEADD UNIVERSAL_GND..1
(3500 -175);
FORCEPROP 3 LASTPIN (3500 -125) SIG_NAME GND\g
J 0
(3510 -115);
DISPLAY 0.659574 (3510 -115);
PAINT MONO (3510 -115);
DISPLAY INVISIBLE (3510 -115);
FORCEPROP 2 LAST CDS_LIB pure_quanta_power
J 0
(3500 -175);
DISPLAY INVISIBLE (3500 -175);
FORCEPROP 1 LAST HDL_POWER GND
J 1
(3525 -250);
DISPLAY 0.872340 (3525 -250);
PAINT GREEN (3525 -250);
DISPLAY INVISIBLE (3525 -250);
FORCEPROP 1 LAST PATH I128
J 0
(3575 -175);
DISPLAY 0.872340 (3575 -175);
PAINT AQUA (3575 -175);
DISPLAY INVISIBLE (3575 -175);
FORCEADD ISL28022FRZT..1
(2925 475);
FORCEPROP 1 LAST LOCATION U276
J 0
(2630 1056);
DISPLAY 0.723404 (2630 1056);
PAINT GREEN (2630 1056);
FORCEPROP 2 LAST SEC 1
J 0
(2650 1200);
DISPLAY 0.680851 (2650 1200);
PAINT MONO (2650 1200);
DISPLAY INVISIBLE (2650 1200);
FORCEPROP 2 LASTPIN (2475 575) $PN 2
J 2
(2465 585);
DISPLAY 0.680851 (2465 585);
PAINT MONO (2465 585);
FORCEPROP 2 LASTPIN (2475 625) $PN 1
J 2
(2465 635);
DISPLAY 0.680851 (2465 635);
PAINT MONO (2465 635);
FORCEPROP 2 LASTPIN (3375 725) $PN 3
J 0
(3385 735);
DISPLAY 0.680851 (3385 735);
PAINT MONO (3385 735);
FORCEPROP 2 LASTPIN (3375 275) $PN 10
J 0
(3385 285);
DISPLAY 0.680851 (3385 285);
PAINT MONO (3385 285);
FORCEPROP 2 LASTPIN (3375 625) $PN 6
J 0
(3385 635);
DISPLAY 0.680851 (3385 635);
PAINT MONO (3385 635);
FORCEPROP 2 LASTPIN (3375 575) $PN 7
J 0
(3385 585);
DISPLAY 0.680851 (3385 585);
PAINT MONO (3385 585);
FORCEPROP 2 LASTPIN (3375 525) $PN 8
J 0
(3385 535);
DISPLAY 0.680851 (3385 535);
PAINT MONO (3385 535);
FORCEPROP 2 LASTPIN (3375 475) $PN 14
J 0
(3385 485);
DISPLAY 0.680851 (3385 485);
PAINT MONO (3385 485);
FORCEPROP 2 LASTPIN (3375 425) $PN 15
J 0
(3385 435);
DISPLAY 0.680851 (3385 435);
PAINT MONO (3385 435);
FORCEPROP 2 LASTPIN (3375 375) $PN 16
J 0
(3385 385);
DISPLAY 0.680851 (3385 385);
PAINT MONO (3385 385);
FORCEPROP 2 LASTPIN (2475 475) $PN 5
J 2
(2465 485);
DISPLAY 0.680851 (2465 485);
PAINT MONO (2465 485);
FORCEPROP 2 LASTPIN (2475 425) $PN 4
J 2
(2465 435);
DISPLAY 0.680851 (2465 435);
PAINT MONO (2465 435);
FORCEPROP 2 LASTPIN (3375 225) $PN TH
J 0
(3385 235);
DISPLAY 0.680851 (3385 235);
PAINT MONO (3385 235);
FORCEPROP 2 LASTPIN (2475 325) $PN 11
J 2
(2465 335);
DISPLAY 0.680851 (2465 335);
PAINT MONO (2465 335);
FORCEPROP 2 LASTPIN (2475 725) $PN 9
J 2
(2465 735);
DISPLAY 0.680851 (2465 735);
PAINT MONO (2465 735);
FORCEPROP 2 LASTPIN (2475 225) $PN 12
J 2
(2465 235);
DISPLAY 0.680851 (2465 235);
PAINT MONO (2465 235);
FORCEPROP 2 LASTPIN (2475 275) $PN 13
J 2
(2465 285);
DISPLAY 0.680851 (2465 285);
PAINT MONO (2465 285);
FORCEPROP 1 LAST MATERIAL IC
J 0
(2630 782);
DISPLAY 0.723404 (2630 782);
PAINT GREEN (2630 782);
FORCEPROP 2 LAST VALUE ISL28022FRZ-T
J 0
(2650 1100);
DISPLAY 1.021277 (2650 1100);
FORCEPROP 2 LAST PART_TYPE SMLF
J 0
(2650 1150);
DISPLAY 1.021277 (2650 1150);
FORCEPROP 2 LAST CDS_LIB pure_quanta
J 0
(2925 475);
DISPLAY INVISIBLE (2925 475);
FORCEPROP 1 LAST NEEDS_NO_SIZE TRUE
J 0
(2925 475);
DISPLAY 0.723404 (2925 475);
PAINT GREEN (2925 475);
DISPLAY INVISIBLE (2925 475);
FORCEPROP 1 LAST CDS_LMAN_SYM_OUTLINE -300,300,300,-300
J 0
(2925 475);
DISPLAY 0.468085 (2925 475);
PAINT GREEN (2925 475);
DISPLAY INVISIBLE (2925 475);
FORCEPROP 2 LAST SEC_TYPE 
J 0
(2650 1200);
DISPLAY 1.021277 (2650 1200);
DISPLAY INVISIBLE (2650 1200);
FORCEPROP 1 LAST PATH I129
J 0
(2925 475);
DISPLAY 0.723404 (2925 475);
PAINT GREEN (2925 475);
DISPLAY INVISIBLE (2925 475);
FORCEPROP 1 LAST PART_NUMBER AL028022003
J 0
(2630 909);
DISPLAY 0.723404 (2630 909);
PAINT GREEN (2630 909);
DISPLAY INVISIBLE (2630 909);
FORCEADD Q_RES..1
(1300 -125);
FORCEPROP 1 LAST LOCATION R3758
J 0
(1050 -125);
DISPLAY 0.638298 (1050 -125);
FORCEPROP 0 LAST $SEC 1
J 0
(1150 -25);
DISPLAY 0.680851 (1150 -25);
PAINT MONO (1150 -25);
DISPLAY INVISIBLE (1150 -25);
FORCEPROP 0 LAST CDS_SEC 1
J 0
(1150 -25);
DISPLAY 1.021277 (1150 -25);
DISPLAY INVISIBLE (1150 -25);
FORCEPROP 1 LASTPIN (1200 -125) $PN 1
J 0
(1212 -113);
DISPLAY 0.787234 (1212 -113);
PAINT MONO (1212 -113);
FORCEPROP 1 LASTPIN (1400 -125) $PN 2
J 0
(1362 -113);
DISPLAY 0.787234 (1362 -113);
PAINT MONO (1362 -113);
FORCEPROP 1 LAST MATERIAL CHIP
J 0
(1325 -225);
DISPLAY 0.638298 (1325 -225);
FORCEPROP 1 LAST VALUE 10
J 2
(1250 -175);
DISPLAY 0.638298 (1250 -175);
FORCEPROP 1 LAST TOLERANCE 1%
J 0
(1350 -175);
DISPLAY 0.638298 (1350 -175);
FORCEPROP 1 LAST PACK_TYPE 0402LF
J 0
(1425 -175);
DISPLAY 0.638298 (1425 -175);
FORCEPROP 1 LAST WATTAGE 1/16W
J 2
(1300 -225);
DISPLAY 0.638298 (1300 -225);
FORCEPROP 2 LAST CDS_LIB pure_quanta
J 0
(1300 -125);
DISPLAY INVISIBLE (1300 -125);
FORCEPROP 1 LAST PATH I132
J 0
(1250 25);
DISPLAY 0.978723 (1250 25);
PAINT WHITE (1250 25);
DISPLAY INVISIBLE (1250 25);
FORCEPROP 1 LAST PART_NUMBER CS01002FB07
J 0
(1150 -75);
DISPLAY 0.638298 (1150 -75);
DISPLAY INVISIBLE (1150 -75);
FORCEADD Q_CAP..1
(1650 -275);
FORCEPROP 1 LAST LOCATION C2071
J 0
(1700 -175);
DISPLAY 0.978723 (1700 -175);
FORCEPROP 0 LAST $SEC 1
J 0
(1700 -125);
DISPLAY 0.680851 (1700 -125);
PAINT MONO (1700 -125);
DISPLAY INVISIBLE (1700 -125);
FORCEPROP 0 LAST CDS_SEC 1
J 0
(1700 -125);
DISPLAY 1.021277 (1700 -125);
DISPLAY INVISIBLE (1700 -125);
FORCEPROP 1 LASTPIN (1650 -175) $PN 1
J 0
(1660 -195);
DISPLAY 0.787234 (1660 -195);
PAINT MONO (1660 -195);
FORCEPROP 1 LASTPIN (1650 -375) $PN 2
J 0
(1660 -395);
DISPLAY 0.787234 (1660 -395);
PAINT MONO (1660 -395);
FORCEPROP 1 LAST PACK_TYPE 0402
J 0
(1700 -350);
DISPLAY 0.510638 (1700 -350);
FORCEPROP 1 LAST VALUE 0.1UF
J 0
(1700 -225);
DISPLAY 0.510638 (1700 -225);
FORCEPROP 1 LAST TOLERANCE 10%
J 0
(1700 -275);
DISPLAY 0.510638 (1700 -275);
FORCEPROP 1 LAST VOLTAGE 25V
J 0
(1700 -250);
DISPLAY 0.510638 (1700 -250);
FORCEPROP 1 LAST MATERIAL X7R
J 0
(1700 -300);
DISPLAY 0.510638 (1700 -300);
FORCEPROP 2 LAST CDS_LIB pure_quanta
J 0
(1650 -275);
DISPLAY INVISIBLE (1650 -275);
FORCEPROP 1 LAST PATH I133
J 0
(1700 -125);
DISPLAY 0.978723 (1700 -125);
PAINT WHITE (1700 -125);
DISPLAY INVISIBLE (1700 -125);
FORCEPROP 1 LAST PART_NUMBER CH4104K1B00
J 0
(1700 -325);
DISPLAY 0.510638 (1700 -325);
DISPLAY INVISIBLE (1700 -325);
FORCEADD Q_RES..1
(1300 -400);
FORCEPROP 1 LAST LOCATION R3760
J 0
(1050 -400);
DISPLAY 0.638298 (1050 -400);
FORCEPROP 0 LAST $SEC 1
J 0
(1150 -300);
DISPLAY 0.680851 (1150 -300);
PAINT MONO (1150 -300);
DISPLAY INVISIBLE (1150 -300);
FORCEPROP 0 LAST CDS_SEC 1
J 0
(1150 -300);
DISPLAY 1.021277 (1150 -300);
DISPLAY INVISIBLE (1150 -300);
FORCEPROP 1 LASTPIN (1200 -400) $PN 1
J 0
(1212 -388);
DISPLAY 0.787234 (1212 -388);
PAINT MONO (1212 -388);
FORCEPROP 1 LASTPIN (1400 -400) $PN 2
J 0
(1362 -388);
DISPLAY 0.787234 (1362 -388);
PAINT MONO (1362 -388);
FORCEPROP 1 LAST MATERIAL CHIP
J 0
(1325 -500);
DISPLAY 0.638298 (1325 -500);
FORCEPROP 1 LAST PACK_TYPE 0402LF
J 0
(1425 -450);
DISPLAY 0.638298 (1425 -450);
FORCEPROP 1 LAST TOLERANCE 1%
J 0
(1350 -450);
DISPLAY 0.638298 (1350 -450);
FORCEPROP 1 LAST VALUE 10
J 2
(1250 -450);
DISPLAY 0.638298 (1250 -450);
FORCEPROP 1 LAST WATTAGE 1/16W
J 2
(1300 -500);
DISPLAY 0.638298 (1300 -500);
FORCEPROP 2 LAST CDS_LIB pure_quanta
J 0
(1300 -400);
DISPLAY INVISIBLE (1300 -400);
FORCEPROP 1 LAST PATH I134
J 0
(1250 -250);
DISPLAY 0.978723 (1250 -250);
PAINT WHITE (1250 -250);
DISPLAY INVISIBLE (1250 -250);
FORCEPROP 1 LAST PART_NUMBER CS01002FB07
J 0
(1150 -350);
DISPLAY 0.638298 (1150 -350);
DISPLAY INVISIBLE (1150 -350);
FORCEADD Q_RES..1
(750 1000);
FORCEPROP 1 LAST LOCATION R3764
J 0
(550 1000);
DISPLAY 0.638298 (550 1000);
FORCEPROP 0 LAST $SEC 1
J 0
(625 1050);
DISPLAY 0.680851 (625 1050);
PAINT MONO (625 1050);
DISPLAY INVISIBLE (625 1050);
FORCEPROP 0 LAST CDS_SEC 1
J 0
(625 1050);
DISPLAY 1.021277 (625 1050);
DISPLAY INVISIBLE (625 1050);
FORCEPROP 1 LASTPIN (650 1000) $PN 1
J 0
(662 1012);
DISPLAY 0.787234 (662 1012);
PAINT MONO (662 1012);
FORCEPROP 1 LASTPIN (850 1000) $PN 2
J 0
(812 1012);
DISPLAY 0.787234 (812 1012);
PAINT MONO (812 1012);
FORCEPROP 1 LAST VALUE 4.7K
J 2
(950 1000);
DISPLAY 0.510638 (950 1000);
FORCEPROP 1 LAST WATTAGE 1/16W
J 2
(1075 1000);
DISPLAY 0.510638 (1075 1000);
FORCEPROP 1 LAST MATERIAL EMPTY
J 0
(1125 1000);
DISPLAY 0.510638 (1125 1000);
PAINT RED (1125 1000);
FORCEPROP 1 LAST PACK_TYPE 0402LF
J 0
(1250 1000);
DISPLAY 0.510638 (1250 1000);
FORCEPROP 1 LAST TOLERANCE 1%
J 0
(1075 1000);
DISPLAY 0.510638 (1075 1000);
FORCEPROP 2 LAST CDS_LIB pure_quanta
J 0
(750 1000);
DISPLAY INVISIBLE (750 1000);
FORCEPROP 1 LAST PATH I135
J 0
(700 1150);
DISPLAY 0.978723 (700 1150);
PAINT WHITE (700 1150);
DISPLAY INVISIBLE (700 1150);
FORCEPROP 1 LAST PART_NUMBER CS24702FB06
J 0
(250 1000);
DISPLAY 0.510638 (250 1000);
DISPLAY INVISIBLE (250 1000);
FORCEADD Q_RES..1
(750 1075);
FORCEPROP 1 LAST LOCATION R3763
J 0
(550 1075);
DISPLAY 0.638298 (550 1075);
FORCEPROP 0 LAST $SEC 1
J 0
(625 1125);
DISPLAY 0.680851 (625 1125);
PAINT MONO (625 1125);
DISPLAY INVISIBLE (625 1125);
FORCEPROP 0 LAST CDS_SEC 1
J 0
(625 1125);
DISPLAY 1.021277 (625 1125);
DISPLAY INVISIBLE (625 1125);
FORCEPROP 1 LASTPIN (650 1075) $PN 1
J 0
(662 1087);
DISPLAY 0.787234 (662 1087);
PAINT MONO (662 1087);
FORCEPROP 1 LASTPIN (850 1075) $PN 2
J 0
(812 1087);
DISPLAY 0.787234 (812 1087);
PAINT MONO (812 1087);
FORCEPROP 1 LAST MATERIAL CHIP
J 0
(1125 1075);
DISPLAY 0.510638 (1125 1075);
FORCEPROP 1 LAST TOLERANCE 1%
J 0
(1075 1075);
DISPLAY 0.510638 (1075 1075);
FORCEPROP 1 LAST WATTAGE 1/16W
J 2
(1075 1075);
DISPLAY 0.510638 (1075 1075);
FORCEPROP 1 LAST VALUE 4.7K
J 2
(950 1075);
DISPLAY 0.510638 (950 1075);
FORCEPROP 1 LAST PACK_TYPE 0402LF
J 0
(1250 1075);
DISPLAY 0.510638 (1250 1075);
FORCEPROP 2 LAST CDS_LIB pure_quanta
J 0
(750 1075);
DISPLAY INVISIBLE (750 1075);
FORCEPROP 1 LAST PATH I136
J 0
(700 1225);
DISPLAY 0.978723 (700 1225);
PAINT WHITE (700 1225);
DISPLAY INVISIBLE (700 1225);
FORCEPROP 1 LAST PART_NUMBER CS24702FB06
J 0
(250 1075);
DISPLAY 0.510638 (250 1075);
DISPLAY INVISIBLE (250 1075);
FORCEADD UNIVERSAL_GND..1
(175 875);
FORCEPROP 3 LASTPIN (175 925) SIG_NAME GND\g
J 0
(185 935);
DISPLAY 0.659574 (185 935);
PAINT MONO (185 935);
DISPLAY INVISIBLE (185 935);
FORCEPROP 2 LAST CDS_LIB pure_quanta_power
J 0
(175 875);
DISPLAY INVISIBLE (175 875);
FORCEPROP 1 LAST HDL_POWER GND
J 1
(200 800);
DISPLAY 0.872340 (200 800);
PAINT GREEN (200 800);
DISPLAY INVISIBLE (200 800);
FORCEPROP 1 LAST PATH I137
J 0
(250 875);
DISPLAY 0.872340 (250 875);
PAINT AQUA (250 875);
DISPLAY INVISIBLE (250 875);
FORCEADD OFFPAGE..1
(75 475);
FORCEPROP 2 LAST $XR0 252 
J 0
(-177 475);
DISPLAY 0.638298 (-177 475);
PAINT MONO (-177 475);
FORCEPROP 2 LAST CDS_LIB standard
J 0
(75 475);
DISPLAY INVISIBLE (75 475);
FORCEPROP 1 LAST OFFPAGE TRUE
J 0
(400 350);
DISPLAY 0.872340 (400 350);
DISPLAY INVISIBLE (400 350);
FORCEPROP 1 LAST COMMENT_BODY TRUE
J 0
(200 375);
DISPLAY 0.872340 (200 375);
PAINT GREEN (200 375);
DISPLAY INVISIBLE (200 375);
FORCEPROP 2 LAST PATH I138
J 0
(-175 525);
DISPLAY 1.021277 (-175 525);
DISPLAY INVISIBLE (-175 525);
FORCEADD OFFPAGE..3
R 2
(75 425);
FORCEPROP 2 LAST $XR0 252 
J 0
(-205 425);
DISPLAY 0.638298 (-205 425);
PAINT MONO (-205 425);
FORCEPROP 2 LAST CDS_LIB standard
J 2
(75 425);
PAINT MONO (75 425);
DISPLAY INVISIBLE (75 425);
FORCEPROP 1 LAST OFFPAGE TRUE
J 2
(-250 300);
DISPLAY 0.872340 (-250 300);
DISPLAY INVISIBLE (-250 300);
FORCEPROP 1 LAST COMMENT_BODY TRUE
J 2
(125 325);
DISPLAY 0.872340 (125 325);
PAINT GREEN (125 325);
DISPLAY INVISIBLE (125 325);
FORCEPROP 2 LAST PATH I139
J 0
(-200 475);
DISPLAY 1.021277 (-200 475);
DISPLAY INVISIBLE (-200 475);
FORCEADD UNIVERSAL_POWER..1
(-100 225);
FORCEPROP 3 LASTPIN (-100 175) SIG_NAME P3V3_E1S_0_R\g
J 0
(-90 185);
DISPLAY 0.659574 (-90 185);
PAINT MONO (-90 185);
DISPLAY INVISIBLE (-90 185);
FORCEPROP 1 LAST HDL_POWER P3V3_E1S_0_R
J 1
(-100 275);
DISPLAY 0.872340 (-100 275);
PAINT GREEN (-100 275);
FORCEPROP 2 LAST CDS_LIB pure_quanta_power
J 0
(-100 225);
DISPLAY INVISIBLE (-100 225);
FORCEPROP 1 LAST PATH I140
J 0
(-50 250);
DISPLAY 0.872340 (-50 250);
PAINT AQUA (-50 250);
DISPLAY INVISIBLE (-50 250);
FORCEADD Q_CAP..1
(-500 650);
FORCEPROP 1 LAST LOCATION C2069
J 0
(-450 750);
DISPLAY 0.978723 (-450 750);
FORCEPROP 0 LAST $SEC 1
J 0
(-450 800);
DISPLAY 0.680851 (-450 800);
PAINT MONO (-450 800);
DISPLAY INVISIBLE (-450 800);
FORCEPROP 0 LAST CDS_SEC 1
J 0
(-450 800);
DISPLAY 1.021277 (-450 800);
DISPLAY INVISIBLE (-450 800);
FORCEPROP 1 LASTPIN (-500 750) $PN 1
J 0
(-490 730);
DISPLAY 0.787234 (-490 730);
PAINT MONO (-490 730);
FORCEPROP 1 LASTPIN (-500 550) $PN 2
J 0
(-490 530);
DISPLAY 0.787234 (-490 530);
PAINT MONO (-490 530);
FORCEPROP 1 LAST VALUE 0.1UF
J 0
(-450 700);
DISPLAY 0.638298 (-450 700);
FORCEPROP 1 LAST PACK_TYPE 0402
J 0
(-450 500);
DISPLAY 0.638298 (-450 500);
FORCEPROP 1 LAST TOLERANCE 10%
J 0
(-450 600);
DISPLAY 0.638298 (-450 600);
FORCEPROP 1 LAST VOLTAGE 25V
J 0
(-450 650);
DISPLAY 0.638298 (-450 650);
FORCEPROP 1 LAST MATERIAL X7R
J 0
(-450 550);
DISPLAY 0.638298 (-450 550);
FORCEPROP 2 LAST CDS_LIB pure_quanta
J 0
(-500 650);
DISPLAY INVISIBLE (-500 650);
FORCEPROP 1 LAST PATH I142
J 0
(-450 800);
DISPLAY 0.978723 (-450 800);
PAINT WHITE (-450 800);
DISPLAY INVISIBLE (-450 800);
FORCEPROP 1 LAST PART_NUMBER CH4104K1B00
J 0
(-450 500);
DISPLAY 0.808511 (-450 500);
DISPLAY INVISIBLE (-450 500);
FORCEADD UNIVERSAL_GND..1
(-500 375);
FORCEPROP 3 LASTPIN (-500 425) SIG_NAME GND\g
J 0
(-490 435);
DISPLAY 0.659574 (-490 435);
PAINT MONO (-490 435);
DISPLAY INVISIBLE (-490 435);
FORCEPROP 2 LAST CDS_LIB pure_quanta_power
J 0
(-500 375);
DISPLAY INVISIBLE (-500 375);
FORCEPROP 1 LAST HDL_POWER GND
J 1
(-475 300);
DISPLAY 0.872340 (-475 300);
PAINT GREEN (-475 300);
DISPLAY INVISIBLE (-475 300);
FORCEPROP 1 LAST PATH I143
J 0
(-425 375);
DISPLAY 0.872340 (-425 375);
PAINT AQUA (-425 375);
DISPLAY INVISIBLE (-425 375);
FORCEADD Q_RES..1
(-600 75);
FORCEPROP 1 LAST LOCATION R3767
J 0
(-775 75);
DISPLAY 0.638298 (-775 75);
FORCEPROP 0 LAST $SEC 1
J 0
(-775 125);
DISPLAY 0.680851 (-775 125);
PAINT MONO (-775 125);
DISPLAY INVISIBLE (-775 125);
FORCEPROP 0 LAST CDS_SEC 1
J 0
(-775 125);
DISPLAY 1.021277 (-775 125);
DISPLAY INVISIBLE (-775 125);
FORCEPROP 1 LASTPIN (-700 75) $PN 1
J 0
(-688 87);
DISPLAY 0.787234 (-688 87);
PAINT MONO (-688 87);
FORCEPROP 1 LASTPIN (-500 75) $PN 2
J 0
(-538 87);
DISPLAY 0.787234 (-538 87);
PAINT MONO (-538 87);
FORCEPROP 1 LAST PACK_TYPE 2512LF
J 0
(-525 -25);
DISPLAY 0.510638 (-525 -25);
FORCEPROP 1 LAST MATERIAL CHIP
J 0
(-600 -75);
DISPLAY 0.510638 (-600 -75);
FORCEPROP 1 LAST TOLERANCE 1%
J 0
(-600 -25);
DISPLAY 0.510638 (-600 -25);
FORCEPROP 1 LAST VALUE 0.002
J 2
(-625 -25);
DISPLAY 0.510638 (-625 -25);
FORCEPROP 1 LAST WATTAGE 2W
J 2
(-625 -75);
DISPLAY 0.510638 (-625 -75);
FORCEPROP 2 LAST CDS_LIB pure_quanta
J 0
(-600 75);
DISPLAY INVISIBLE (-600 75);
FORCEPROP 1 LAST PATH I144
J 0
(-650 225);
DISPLAY 0.978723 (-650 225);
PAINT WHITE (-650 225);
DISPLAY INVISIBLE (-650 225);
FORCEPROP 1 LAST PART_NUMBER CS+002AFR06
J 0
(-725 25);
DISPLAY 0.510638 (-725 25);
DISPLAY INVISIBLE (-725 25);
FORCEADD UNIVERSAL_POWER..1
(-1175 225);
FORCEPROP 3 LASTPIN (-1175 175) SIG_NAME P3V3_E1S_0\g
J 0
(-1165 185);
DISPLAY 0.659574 (-1165 185);
PAINT MONO (-1165 185);
DISPLAY INVISIBLE (-1165 185);
FORCEPROP 1 LAST HDL_POWER P3V3_E1S_0
J 1
(-1175 275);
DISPLAY 0.872340 (-1175 275);
PAINT GREEN (-1175 275);
FORCEPROP 2 LAST CDS_LIB pure_quanta_power
J 0
(-1175 225);
DISPLAY INVISIBLE (-1175 225);
FORCEPROP 1 LAST PATH I145
J 0
(-1125 250);
DISPLAY 0.872340 (-1125 250);
PAINT AQUA (-1125 250);
DISPLAY INVISIBLE (-1125 250);
FORCEADD Q_RES..2
(1550 825);
FORCEPROP 1 LAST LOCATION R3751
J 0
(1625 900);
DISPLAY 0.978723 (1625 900);
FORCEPROP 0 LAST $SEC 1
J 0
(1625 950);
DISPLAY 0.680851 (1625 950);
PAINT MONO (1625 950);
DISPLAY INVISIBLE (1625 950);
FORCEPROP 0 LAST CDS_SEC 1
J 0
(1625 950);
DISPLAY 1.021277 (1625 950);
DISPLAY INVISIBLE (1625 950);
FORCEPROP 1 LASTPIN (1550 925) $PN 1
J 0
(1555 887);
DISPLAY 0.787234 (1555 887);
PAINT MONO (1555 887);
FORCEPROP 1 LASTPIN (1550 725) $PN 2
J 0
(1555 735);
DISPLAY 0.787234 (1555 735);
PAINT MONO (1555 735);
FORCEPROP 1 LAST WATTAGE 1/16W
J 0
(1625 825);
DISPLAY 0.404255 (1625 825);
FORCEPROP 1 LAST MATERIAL CHIP
J 0
(1625 800);
DISPLAY 0.404255 (1625 800);
FORCEPROP 1 LAST TOLERANCE 5%
J 0
(1625 850);
DISPLAY 0.404255 (1625 850);
FORCEPROP 1 LAST VALUE 0
J 0
(1625 875);
DISPLAY 0.404255 (1625 875);
FORCEPROP 1 LAST PACK_TYPE 0402LF
J 0
(1625 750);
DISPLAY 0.404255 (1625 750);
FORCEPROP 2 LAST CDS_LIB pure_quanta
J 0
(1550 825);
DISPLAY INVISIBLE (1550 825);
FORCEPROP 1 LAST PATH I146
J 0
(1600 1000);
DISPLAY 0.978723 (1600 1000);
PAINT WHITE (1600 1000);
DISPLAY INVISIBLE (1600 1000);
FORCEPROP 1 LAST PART_NUMBER CS00002JB13
J 0
(1625 775);
DISPLAY 0.404255 (1625 775);
DISPLAY INVISIBLE (1625 775);
FORCEADD UNIVERSAL_POWER..1
(-250 975);
FORCEPROP 3 LASTPIN (-250 925) SIG_NAME P3V3_E1S_0_R\g
J 0
(-240 935);
DISPLAY 0.659574 (-240 935);
PAINT MONO (-240 935);
DISPLAY INVISIBLE (-240 935);
FORCEPROP 1 LAST HDL_POWER P3V3_E1S_0_R
J 1
(-250 1025);
DISPLAY 0.872340 (-250 1025);
PAINT GREEN (-250 1025);
FORCEPROP 2 LAST CDS_LIB pure_quanta_power
J 0
(-250 975);
DISPLAY INVISIBLE (-250 975);
FORCEPROP 1 LAST PATH I147
J 0
(-200 1000);
DISPLAY 0.872340 (-200 1000);
PAINT AQUA (-200 1000);
DISPLAY INVISIBLE (-200 1000);
FORCEADD UNIVERSAL_POWER..1
(4225 1375);
FORCEPROP 3 LASTPIN (4225 1325) SIG_NAME P3V3_AUX\g
J 0
(4235 1335);
DISPLAY 0.659574 (4235 1335);
PAINT MONO (4235 1335);
DISPLAY INVISIBLE (4235 1335);
FORCEPROP 1 LAST HDL_POWER P3V3_AUX
J 1
(4225 1425);
DISPLAY 0.872340 (4225 1425);
PAINT GREEN (4225 1425);
FORCEPROP 2 LAST CDS_LIB pure_quanta_power
J 0
(4225 1375);
DISPLAY INVISIBLE (4225 1375);
FORCEPROP 1 LAST PATH I148
J 0
(4275 1400);
DISPLAY 0.872340 (4275 1400);
PAINT AQUA (4275 1400);
DISPLAY INVISIBLE (4275 1400);
FORCEADD Q_RES..2
(4225 1175);
FORCEPROP 1 LAST LOCATION R4093
J 0
(4270 1300);
DISPLAY 0.978723 (4270 1300);
FORCEPROP 0 LAST $SEC 1
J 0
(4275 1350);
DISPLAY 0.680851 (4275 1350);
PAINT MONO (4275 1350);
DISPLAY INVISIBLE (4275 1350);
FORCEPROP 0 LAST CDS_SEC 1
J 0
(4275 1350);
DISPLAY 1.021277 (4275 1350);
DISPLAY INVISIBLE (4275 1350);
FORCEPROP 1 LASTPIN (4225 1275) $PN 1
J 0
(4230 1237);
DISPLAY 0.787234 (4230 1237);
PAINT MONO (4230 1237);
FORCEPROP 1 LASTPIN (4225 1075) $PN 2
J 0
(4230 1085);
DISPLAY 0.787234 (4230 1085);
PAINT MONO (4230 1085);
FORCEPROP 1 LAST TOLERANCE 1%
J 0
(4270 1200);
DISPLAY 0.787234 (4270 1200);
FORCEPROP 1 LAST VALUE 1K
J 0
(4270 1250);
DISPLAY 0.787234 (4270 1250);
FORCEPROP 1 LAST WATTAGE 1/16W
J 0
(4265 1150);
DISPLAY 0.787234 (4265 1150);
FORCEPROP 1 LAST MATERIAL CHIP
J 0
(4265 1100);
DISPLAY 0.787234 (4265 1100);
FORCEPROP 1 LAST PACK_TYPE 0402LF
J 0
(4265 1000);
DISPLAY 0.787234 (4265 1000);
FORCEPROP 2 LAST CDS_LIB pure_quanta
J 0
(4225 1175);
DISPLAY INVISIBLE (4225 1175);
FORCEPROP 1 LAST PATH I149
J 0
(4275 1350);
DISPLAY 0.978723 (4275 1350);
PAINT WHITE (4275 1350);
DISPLAY INVISIBLE (4275 1350);
FORCEPROP 1 LAST PART_NUMBER CS21002FB06
J 0
(4265 1050);
DISPLAY 0.787234 (4265 1050);
DISPLAY INVISIBLE (4265 1050);
FORCEADD UNIVERSAL_POWER..1
(4250 3975);
FORCEPROP 3 LASTPIN (4250 3925) SIG_NAME P3V3_AUX\g
J 0
(4260 3935);
DISPLAY 0.659574 (4260 3935);
PAINT MONO (4260 3935);
DISPLAY INVISIBLE (4260 3935);
FORCEPROP 1 LAST HDL_POWER P3V3_AUX
J 1
(4250 4025);
DISPLAY 0.872340 (4250 4025);
PAINT GREEN (4250 4025);
FORCEPROP 2 LAST CDS_LIB pure_quanta_power
J 0
(4250 3975);
DISPLAY INVISIBLE (4250 3975);
FORCEPROP 1 LAST PATH I150
J 0
(4300 4000);
DISPLAY 0.872340 (4300 4000);
PAINT AQUA (4300 4000);
DISPLAY INVISIBLE (4300 4000);
FORCEADD Q_RES..2
(4250 3775);
FORCEPROP 1 LAST LOCATION R4094
J 0
(4295 3900);
DISPLAY 0.978723 (4295 3900);
FORCEPROP 0 LAST $SEC 1
J 0
(4300 3950);
DISPLAY 0.680851 (4300 3950);
PAINT MONO (4300 3950);
DISPLAY INVISIBLE (4300 3950);
FORCEPROP 0 LAST CDS_SEC 1
J 0
(4300 3950);
DISPLAY 1.021277 (4300 3950);
DISPLAY INVISIBLE (4300 3950);
FORCEPROP 1 LASTPIN (4250 3875) $PN 1
J 0
(4255 3837);
DISPLAY 0.787234 (4255 3837);
PAINT MONO (4255 3837);
FORCEPROP 1 LASTPIN (4250 3675) $PN 2
J 0
(4255 3685);
DISPLAY 0.787234 (4255 3685);
PAINT MONO (4255 3685);
FORCEPROP 1 LAST TOLERANCE 1%
J 0
(4295 3800);
DISPLAY 0.787234 (4295 3800);
FORCEPROP 1 LAST WATTAGE 1/16W
J 0
(4290 3750);
DISPLAY 0.787234 (4290 3750);
FORCEPROP 1 LAST MATERIAL CHIP
J 0
(4290 3700);
DISPLAY 0.787234 (4290 3700);
FORCEPROP 1 LAST VALUE 1K
J 0
(4295 3850);
DISPLAY 0.787234 (4295 3850);
FORCEPROP 1 LAST PACK_TYPE 0402LF
J 0
(4290 3600);
DISPLAY 0.787234 (4290 3600);
FORCEPROP 2 LAST CDS_LIB pure_quanta
J 0
(4250 3775);
DISPLAY INVISIBLE (4250 3775);
FORCEPROP 1 LAST PATH I151
J 0
(4300 3950);
DISPLAY 0.978723 (4300 3950);
PAINT WHITE (4300 3950);
DISPLAY INVISIBLE (4300 3950);
FORCEPROP 1 LAST PART_NUMBER CS21002FB06
J 0
(4290 3650);
DISPLAY 0.787234 (4290 3650);
DISPLAY INVISIBLE (4290 3650);
FORCEADD Q_RES..1
(1275 3075);
FORCEPROP 1 LAST LOCATION R3600
J 0
(1000 3075);
DISPLAY 0.787234 (1000 3075);
FORCEPROP 0 LAST $SEC 1
J 0
(1450 3175);
DISPLAY 0.680851 (1450 3175);
PAINT MONO (1450 3175);
DISPLAY INVISIBLE (1450 3175);
FORCEPROP 0 LAST CDS_SEC 1
J 0
(1450 3175);
DISPLAY 0.680851 (1450 3175);
DISPLAY INVISIBLE (1450 3175);
FORCEPROP 1 LASTPIN (1175 3075) $PN 1
J 0
(1187 3087);
DISPLAY 0.787234 (1187 3087);
PAINT MONO (1187 3087);
FORCEPROP 1 LASTPIN (1375 3075) $PN 2
J 0
(1337 3087);
DISPLAY 0.787234 (1337 3087);
PAINT MONO (1337 3087);
FORCEPROP 1 LAST PACK_TYPE 0402LF
J 0
(1175 3150);
DISPLAY 0.404255 (1175 3150);
FORCEPROP 1 LAST WATTAGE 1/16W
J 2
(1450 3150);
DISPLAY 0.510638 (1450 3150);
FORCEPROP 1 LAST VALUE 0
J 2
(1450 3075);
DISPLAY 0.638298 (1450 3075);
FORCEPROP 1 LAST TOLERANCE 5%
J 0
(1475 3075);
DISPLAY 0.638298 (1475 3075);
FORCEPROP 1 LAST MATERIAL CHIP
J 0
(1575 3075);
DISPLAY 0.638298 (1575 3075);
FORCEPROP 2 LAST CDS_LIB pure_quanta
J 0
(1275 3075);
DISPLAY INVISIBLE (1275 3075);
FORCEPROP 1 LAST PATH I152
J 0
(1225 3225);
DISPLAY 0.978723 (1225 3225);
PAINT WHITE (1225 3225);
DISPLAY INVISIBLE (1225 3225);
FORCEPROP 1 LAST PART_NUMBER CS00002JB13
J 0
(1175 3125);
DISPLAY 0.404255 (1175 3125);
DISPLAY INVISIBLE (1175 3125);
FORCEADD Q_RES..1
(1275 3025);
FORCEPROP 1 LAST LOCATION R3601
J 0
(1000 3025);
DISPLAY 0.787234 (1000 3025);
FORCEPROP 0 LAST $SEC 1
J 0
(1575 3075);
DISPLAY 0.680851 (1575 3075);
PAINT MONO (1575 3075);
DISPLAY INVISIBLE (1575 3075);
FORCEPROP 0 LAST CDS_SEC 1
J 0
(1575 3075);
DISPLAY 0.680851 (1575 3075);
DISPLAY INVISIBLE (1575 3075);
FORCEPROP 1 LASTPIN (1175 3025) $PN 1
J 0
(1187 3037);
DISPLAY 0.787234 (1187 3037);
PAINT MONO (1187 3037);
FORCEPROP 1 LASTPIN (1375 3025) $PN 2
J 0
(1337 3037);
DISPLAY 0.787234 (1337 3037);
PAINT MONO (1337 3037);
FORCEPROP 1 LAST MATERIAL CHIP
J 0
(1575 3025);
DISPLAY 0.638298 (1575 3025);
FORCEPROP 1 LAST TOLERANCE 5%
J 0
(1475 3025);
DISPLAY 0.638298 (1475 3025);
FORCEPROP 1 LAST VALUE 0
J 2
(1450 3025);
DISPLAY 0.638298 (1450 3025);
FORCEPROP 1 LAST WATTAGE 1/16W
J 2
(1450 3100);
DISPLAY 0.510638 (1450 3100);
DISPLAY INVISIBLE (1450 3100);
FORCEPROP 1 LAST PACK_TYPE 0402LF
J 0
(1175 3100);
DISPLAY 0.404255 (1175 3100);
DISPLAY INVISIBLE (1175 3100);
FORCEPROP 2 LAST CDS_LIB pure_quanta
J 0
(1275 3025);
DISPLAY INVISIBLE (1275 3025);
FORCEPROP 1 LAST PATH I153
J 0
(1225 3175);
DISPLAY 0.978723 (1225 3175);
PAINT WHITE (1225 3175);
DISPLAY INVISIBLE (1225 3175);
FORCEPROP 1 LAST PART_NUMBER CS00002JB13
J 0
(1175 3075);
DISPLAY 0.404255 (1175 3075);
DISPLAY INVISIBLE (1175 3075);
FORCEADD Q_RES..1
(1275 425);
FORCEPROP 1 LAST LOCATION R3756
J 0
(1000 425);
DISPLAY 0.787234 (1000 425);
FORCEPROP 0 LAST $SEC 1
J 0
(1575 475);
DISPLAY 0.680851 (1575 475);
PAINT MONO (1575 475);
DISPLAY INVISIBLE (1575 475);
FORCEPROP 0 LAST CDS_SEC 1
J 0
(1575 475);
DISPLAY 0.680851 (1575 475);
DISPLAY INVISIBLE (1575 475);
FORCEPROP 1 LASTPIN (1175 425) $PN 1
J 0
(1187 437);
DISPLAY 0.787234 (1187 437);
PAINT MONO (1187 437);
FORCEPROP 1 LASTPIN (1375 425) $PN 2
J 0
(1337 437);
DISPLAY 0.787234 (1337 437);
PAINT MONO (1337 437);
FORCEPROP 1 LAST VALUE 0
J 2
(1450 425);
DISPLAY 0.638298 (1450 425);
FORCEPROP 1 LAST TOLERANCE 5%
J 0
(1475 425);
DISPLAY 0.638298 (1475 425);
FORCEPROP 1 LAST MATERIAL CHIP
J 0
(1575 425);
DISPLAY 0.638298 (1575 425);
FORCEPROP 1 LAST PACK_TYPE 0402LF
J 0
(1175 500);
DISPLAY 0.404255 (1175 500);
DISPLAY INVISIBLE (1175 500);
FORCEPROP 1 LAST WATTAGE 1/16W
J 2
(1450 500);
DISPLAY 0.510638 (1450 500);
DISPLAY INVISIBLE (1450 500);
FORCEPROP 2 LAST CDS_LIB pure_quanta
J 0
(1275 425);
DISPLAY INVISIBLE (1275 425);
FORCEPROP 1 LAST PATH I154
J 0
(1225 575);
DISPLAY 0.978723 (1225 575);
PAINT WHITE (1225 575);
DISPLAY INVISIBLE (1225 575);
FORCEPROP 1 LAST PART_NUMBER CS00002JB13
J 0
(1175 475);
DISPLAY 0.404255 (1175 475);
DISPLAY INVISIBLE (1175 475);
FORCEADD Q_RES..1
(1275 475);
FORCEPROP 1 LAST LOCATION R3754
J 0
(1000 475);
DISPLAY 0.787234 (1000 475);
FORCEPROP 0 LAST $SEC 1
J 0
(1450 575);
DISPLAY 0.680851 (1450 575);
PAINT MONO (1450 575);
DISPLAY INVISIBLE (1450 575);
FORCEPROP 0 LAST CDS_SEC 1
J 0
(1450 575);
DISPLAY 0.680851 (1450 575);
DISPLAY INVISIBLE (1450 575);
FORCEPROP 1 LASTPIN (1175 475) $PN 1
J 0
(1187 487);
DISPLAY 0.787234 (1187 487);
PAINT MONO (1187 487);
FORCEPROP 1 LASTPIN (1375 475) $PN 2
J 0
(1337 487);
DISPLAY 0.787234 (1337 487);
PAINT MONO (1337 487);
FORCEPROP 1 LAST WATTAGE 1/16W
J 2
(1450 550);
DISPLAY 0.510638 (1450 550);
FORCEPROP 1 LAST PACK_TYPE 0402LF
J 0
(1175 550);
DISPLAY 0.404255 (1175 550);
FORCEPROP 1 LAST MATERIAL CHIP
J 0
(1575 475);
DISPLAY 0.638298 (1575 475);
FORCEPROP 1 LAST TOLERANCE 5%
J 0
(1475 475);
DISPLAY 0.638298 (1475 475);
FORCEPROP 1 LAST VALUE 0
J 2
(1450 475);
DISPLAY 0.638298 (1450 475);
FORCEPROP 2 LAST CDS_LIB pure_quanta
J 0
(1275 475);
DISPLAY INVISIBLE (1275 475);
FORCEPROP 1 LAST PATH I155
J 0
(1225 625);
DISPLAY 0.978723 (1225 625);
PAINT WHITE (1225 625);
DISPLAY INVISIBLE (1225 625);
FORCEPROP 1 LAST PART_NUMBER CS00002JB13
J 0
(1175 525);
DISPLAY 0.404255 (1175 525);
DISPLAY INVISIBLE (1175 525);
FORCEADD ISL28022FRZT..1
(2925 3075);
FORCEPROP 1 LAST LOCATION U266
J 0
(2630 3656);
DISPLAY 0.723404 (2630 3656);
PAINT GREEN (2630 3656);
FORCEPROP 2 LAST SEC 1
J 0
(2650 3800);
DISPLAY 0.680851 (2650 3800);
PAINT MONO (2650 3800);
DISPLAY INVISIBLE (2650 3800);
FORCEPROP 2 LASTPIN (2475 3175) $PN 2
J 2
(2465 3185);
DISPLAY 0.680851 (2465 3185);
PAINT MONO (2465 3185);
FORCEPROP 2 LASTPIN (2475 3225) $PN 1
J 2
(2465 3235);
DISPLAY 0.680851 (2465 3235);
PAINT MONO (2465 3235);
FORCEPROP 2 LASTPIN (3375 3325) $PN 3
J 0
(3385 3335);
DISPLAY 0.680851 (3385 3335);
PAINT MONO (3385 3335);
FORCEPROP 2 LASTPIN (3375 2875) $PN 10
J 0
(3385 2885);
DISPLAY 0.680851 (3385 2885);
PAINT MONO (3385 2885);
FORCEPROP 2 LASTPIN (3375 3225) $PN 6
J 0
(3385 3235);
DISPLAY 0.680851 (3385 3235);
PAINT MONO (3385 3235);
FORCEPROP 2 LASTPIN (3375 3175) $PN 7
J 0
(3385 3185);
DISPLAY 0.680851 (3385 3185);
PAINT MONO (3385 3185);
FORCEPROP 2 LASTPIN (3375 3125) $PN 8
J 0
(3385 3135);
DISPLAY 0.680851 (3385 3135);
PAINT MONO (3385 3135);
FORCEPROP 2 LASTPIN (3375 3075) $PN 14
J 0
(3385 3085);
DISPLAY 0.680851 (3385 3085);
PAINT MONO (3385 3085);
FORCEPROP 2 LASTPIN (3375 3025) $PN 15
J 0
(3385 3035);
DISPLAY 0.680851 (3385 3035);
PAINT MONO (3385 3035);
FORCEPROP 2 LASTPIN (3375 2975) $PN 16
J 0
(3385 2985);
DISPLAY 0.680851 (3385 2985);
PAINT MONO (3385 2985);
FORCEPROP 2 LASTPIN (2475 3075) $PN 5
J 2
(2465 3085);
DISPLAY 0.680851 (2465 3085);
PAINT MONO (2465 3085);
FORCEPROP 2 LASTPIN (2475 3025) $PN 4
J 2
(2465 3035);
DISPLAY 0.680851 (2465 3035);
PAINT MONO (2465 3035);
FORCEPROP 2 LASTPIN (3375 2825) $PN TH
J 0
(3385 2835);
DISPLAY 0.680851 (3385 2835);
PAINT MONO (3385 2835);
FORCEPROP 2 LASTPIN (2475 2925) $PN 11
J 2
(2465 2935);
DISPLAY 0.680851 (2465 2935);
PAINT MONO (2465 2935);
FORCEPROP 2 LASTPIN (2475 3325) $PN 9
J 2
(2465 3335);
DISPLAY 0.680851 (2465 3335);
PAINT MONO (2465 3335);
FORCEPROP 2 LASTPIN (2475 2825) $PN 12
J 2
(2465 2835);
DISPLAY 0.680851 (2465 2835);
PAINT MONO (2465 2835);
FORCEPROP 2 LASTPIN (2475 2875) $PN 13
J 2
(2465 2885);
DISPLAY 0.680851 (2465 2885);
PAINT MONO (2465 2885);
FORCEPROP 2 LAST PART_TYPE SMLF
J 0
(2650 3750);
DISPLAY 1.021277 (2650 3750);
FORCEPROP 1 LAST MATERIAL IC
J 0
(2630 3382);
DISPLAY 0.723404 (2630 3382);
PAINT GREEN (2630 3382);
FORCEPROP 2 LAST VALUE ISL28022FRZ-T
J 0
(2650 3700);
DISPLAY 1.021277 (2650 3700);
FORCEPROP 2 LAST SEC_TYPE 
J 0
(2650 3800);
DISPLAY 1.021277 (2650 3800);
DISPLAY INVISIBLE (2650 3800);
FORCEPROP 1 LAST CDS_LMAN_SYM_OUTLINE -300,300,300,-300
J 0
(2925 3075);
DISPLAY 0.468085 (2925 3075);
PAINT GREEN (2925 3075);
DISPLAY INVISIBLE (2925 3075);
FORCEPROP 1 LAST NEEDS_NO_SIZE TRUE
J 0
(2925 3075);
DISPLAY 0.723404 (2925 3075);
PAINT GREEN (2925 3075);
DISPLAY INVISIBLE (2925 3075);
FORCEPROP 2 LAST CDS_LIB pure_quanta
J 0
(2925 3075);
DISPLAY INVISIBLE (2925 3075);
FORCEPROP 1 LAST PATH I30
J 0
(2925 3075);
DISPLAY 0.723404 (2925 3075);
PAINT GREEN (2925 3075);
DISPLAY INVISIBLE (2925 3075);
FORCEPROP 1 LAST PART_NUMBER AL028022003
J 0
(2630 3509);
DISPLAY 0.723404 (2630 3509);
PAINT GREEN (2630 3509);
DISPLAY INVISIBLE (2630 3509);
FORCEADD Q_RES..1
(625 3350);
FORCEPROP 1 LAST LOCATION R3616
J 0
(500 3350);
DISPLAY 0.638298 (500 3350);
FORCEPROP 0 LAST $SEC 1
J 0
(500 3400);
DISPLAY 0.680851 (500 3400);
PAINT MONO (500 3400);
DISPLAY INVISIBLE (500 3400);
FORCEPROP 0 LAST CDS_SEC 1
J 0
(500 3400);
DISPLAY 1.021277 (500 3400);
DISPLAY INVISIBLE (500 3400);
FORCEPROP 1 LASTPIN (525 3350) $PN 1
J 0
(537 3362);
DISPLAY 0.787234 (537 3362);
PAINT MONO (537 3362);
FORCEPROP 1 LASTPIN (725 3350) $PN 2
J 0
(687 3362);
DISPLAY 0.787234 (687 3362);
PAINT MONO (687 3362);
FORCEPROP 1 LAST PACK_TYPE 0402LF
J 0
(1100 3350);
DISPLAY 0.510638 (1100 3350);
FORCEPROP 1 LAST MATERIAL CHIP
J 0
(1000 3350);
DISPLAY 0.510638 (1000 3350);
FORCEPROP 1 LAST VALUE 4.7K
J 2
(825 3350);
DISPLAY 0.510638 (825 3350);
FORCEPROP 1 LAST TOLERANCE 1%
J 0
(950 3350);
DISPLAY 0.510638 (950 3350);
FORCEPROP 1 LAST WATTAGE 1/16W
J 2
(950 3350);
DISPLAY 0.510638 (950 3350);
FORCEPROP 2 LAST CDS_LIB pure_quanta
J 0
(625 3350);
DISPLAY INVISIBLE (625 3350);
FORCEPROP 1 LAST PATH I31
J 0
(575 3500);
DISPLAY 0.978723 (575 3500);
PAINT WHITE (575 3500);
DISPLAY INVISIBLE (575 3500);
FORCEPROP 1 LAST PART_NUMBER CS24702FB06
J 0
(200 3350);
DISPLAY 0.510638 (200 3350);
DISPLAY INVISIBLE (200 3350);
FORCEADD OFFPAGE..2
(5900 3325);
FORCEPROP 2 LAST $XR1 82 
J 0
(6209 3325);
DISPLAY 0.638298 (6209 3325);
PAINT MONO (6209 3325);
FORCEPROP 2 LAST $XR0 358 
J 0
(6089 3325);
DISPLAY 0.638298 (6089 3325);
PAINT MONO (6089 3325);
FORCEPROP 2 LAST CDS_LIB standard
J 0
(5900 3325);
DISPLAY INVISIBLE (5900 3325);
FORCEPROP 1 LAST OFFPAGE TRUE
J 0
(6225 3200);
DISPLAY 0.872340 (6225 3200);
DISPLAY INVISIBLE (6225 3200);
FORCEPROP 1 LAST COMMENT_BODY TRUE
J 0
(5855 3230);
DISPLAY 0.872340 (5855 3230);
PAINT GREEN (5855 3230);
DISPLAY INVISIBLE (5855 3230);
FORCEPROP 2 LAST PATH I32
J 0
(6075 3400);
DISPLAY 1.021277 (6075 3400);
DISPLAY INVISIBLE (6075 3400);
FORCEADD UNIVERSAL_POWER..1
(2425 4075);
FORCEPROP 3 LASTPIN (2425 4025) SIG_NAME P3V3_AUX\g
J 0
(2435 4035);
DISPLAY 0.659574 (2435 4035);
PAINT MONO (2435 4035);
DISPLAY INVISIBLE (2435 4035);
FORCEPROP 1 LAST HDL_POWER P3V3_AUX
J 1
(2425 4125);
DISPLAY 0.872340 (2425 4125);
PAINT GREEN (2425 4125);
FORCEPROP 2 LAST CDS_LIB pure_quanta_power
J 0
(2425 4075);
DISPLAY INVISIBLE (2425 4075);
FORCEPROP 1 LAST PATH I33
J 0
(2475 4100);
DISPLAY 0.872340 (2475 4100);
PAINT AQUA (2475 4100);
DISPLAY INVISIBLE (2475 4100);
FORCEADD Q_CAP..1
(2175 3675);
FORCEPROP 1 LAST LOCATION C2015
J 0
(2225 3775);
DISPLAY 0.978723 (2225 3775);
FORCEPROP 0 LAST $SEC 1
J 0
(2225 3825);
DISPLAY 0.680851 (2225 3825);
PAINT MONO (2225 3825);
DISPLAY INVISIBLE (2225 3825);
FORCEPROP 0 LAST CDS_SEC 1
J 0
(2225 3825);
DISPLAY 1.021277 (2225 3825);
DISPLAY INVISIBLE (2225 3825);
FORCEPROP 1 LASTPIN (2175 3775) $PN 1
J 0
(2185 3755);
DISPLAY 0.787234 (2185 3755);
PAINT MONO (2185 3755);
FORCEPROP 1 LASTPIN (2175 3575) $PN 2
J 0
(2185 3555);
DISPLAY 0.787234 (2185 3555);
PAINT MONO (2185 3555);
FORCEPROP 1 LAST VALUE 0.1UF
J 0
(2225 3725);
DISPLAY 0.638298 (2225 3725);
FORCEPROP 1 LAST VOLTAGE 25V
J 0
(2225 3675);
DISPLAY 0.638298 (2225 3675);
FORCEPROP 1 LAST MATERIAL X7R
J 0
(2225 3575);
DISPLAY 0.638298 (2225 3575);
FORCEPROP 1 LAST TOLERANCE 10%
J 0
(2225 3625);
DISPLAY 0.638298 (2225 3625);
FORCEPROP 1 LAST PACK_TYPE 0402
J 0
(2225 3525);
DISPLAY 0.638298 (2225 3525);
FORCEPROP 2 LAST CDS_LIB pure_quanta
J 0
(2175 3675);
DISPLAY INVISIBLE (2175 3675);
FORCEPROP 1 LAST PATH I34
J 0
(2225 3825);
DISPLAY 0.978723 (2225 3825);
PAINT WHITE (2225 3825);
DISPLAY INVISIBLE (2225 3825);
FORCEPROP 1 LAST PART_NUMBER CH4104K1B00
J 0
(2225 3525);
DISPLAY 0.808511 (2225 3525);
DISPLAY INVISIBLE (2225 3525);
FORCEADD Q_RES..1
(4450 3325);
FORCEPROP 1 LAST LOCATION R3563
J 0
(4275 3325);
DISPLAY 0.510638 (4275 3325);
FORCEPROP 0 LAST $SEC 1
J 0
(4750 3375);
DISPLAY 0.680851 (4750 3375);
PAINT MONO (4750 3375);
DISPLAY INVISIBLE (4750 3375);
FORCEPROP 0 LAST CDS_SEC 1
J 0
(4750 3375);
DISPLAY 1.021277 (4750 3375);
DISPLAY INVISIBLE (4750 3375);
FORCEPROP 1 LASTPIN (4350 3325) $PN 1
J 0
(4362 3337);
DISPLAY 0.787234 (4362 3337);
PAINT MONO (4362 3337);
FORCEPROP 1 LASTPIN (4550 3325) $PN 2
J 0
(4512 3337);
DISPLAY 0.787234 (4512 3337);
PAINT MONO (4512 3337);
FORCEPROP 1 LAST MATERIAL CHIP
J 0
(4625 3325);
DISPLAY 0.574468 (4625 3325);
FORCEPROP 1 LAST VALUE 0
J 2
(4600 3325);
DISPLAY 0.574468 (4600 3325);
FORCEPROP 1 LAST PACK_TYPE 0402LF
J 0
(4750 3325);
DISPLAY 0.574468 (4750 3325);
FORCEPROP 1 LAST WATTAGE 1/16W
J 2
(4525 3250);
DISPLAY 0.723404 (4525 3250);
PAINT SKYBLUE (4525 3250);
DISPLAY INVISIBLE (4525 3250);
FORCEPROP 1 LAST TOLERANCE 5%
J 0
(4250 3250);
DISPLAY 0.723404 (4250 3250);
PAINT SKYBLUE (4250 3250);
DISPLAY INVISIBLE (4250 3250);
FORCEPROP 2 LAST CDS_LIB pure_quanta
J 0
(4450 3325);
DISPLAY INVISIBLE (4450 3325);
FORCEPROP 1 LAST PATH I35
J 0
(4400 3475);
DISPLAY 0.978723 (4400 3475);
PAINT WHITE (4400 3475);
DISPLAY INVISIBLE (4400 3475);
FORCEPROP 1 LAST PART_NUMBER CS00002JB13
J 0
(4175 3200);
DISPLAY 0.723404 (4175 3200);
PAINT WHITE (4175 3200);
DISPLAY INVISIBLE (4175 3200);
FORCEADD UNIVERSAL_GND..1
(3500 2425);
FORCEPROP 3 LASTPIN (3500 2475) SIG_NAME GND\g
J 0
(3510 2485);
DISPLAY 0.659574 (3510 2485);
PAINT MONO (3510 2485);
DISPLAY INVISIBLE (3510 2485);
FORCEPROP 2 LAST CDS_LIB pure_quanta_power
J 0
(3500 2425);
DISPLAY INVISIBLE (3500 2425);
FORCEPROP 1 LAST HDL_POWER GND
J 1
(3525 2350);
DISPLAY 0.872340 (3525 2350);
PAINT GREEN (3525 2350);
DISPLAY INVISIBLE (3525 2350);
FORCEPROP 1 LAST PATH I36
J 0
(3575 2425);
DISPLAY 0.872340 (3575 2425);
PAINT AQUA (3575 2425);
DISPLAY INVISIBLE (3575 2425);
FORCEADD UNIVERSAL_GND..1
(2175 3400);
FORCEPROP 3 LASTPIN (2175 3450) SIG_NAME GND\g
J 0
(2185 3460);
DISPLAY 0.659574 (2185 3460);
PAINT MONO (2185 3460);
DISPLAY INVISIBLE (2185 3460);
FORCEPROP 2 LAST CDS_LIB pure_quanta_power
J 0
(2175 3400);
DISPLAY INVISIBLE (2175 3400);
FORCEPROP 1 LAST HDL_POWER GND
J 1
(2200 3325);
DISPLAY 0.872340 (2200 3325);
PAINT GREEN (2200 3325);
DISPLAY INVISIBLE (2200 3325);
FORCEPROP 1 LAST PATH I37
J 0
(2250 3400);
DISPLAY 0.872340 (2250 3400);
PAINT AQUA (2250 3400);
DISPLAY INVISIBLE (2250 3400);
FORCEADD Q_RES..1
(625 3275);
FORCEPROP 1 LAST LOCATION R3617
J 0
(500 3275);
DISPLAY 0.638298 (500 3275);
FORCEPROP 0 LAST $SEC 1
J 0
(500 3325);
DISPLAY 0.680851 (500 3325);
PAINT MONO (500 3325);
DISPLAY INVISIBLE (500 3325);
FORCEPROP 0 LAST CDS_SEC 1
J 0
(500 3325);
DISPLAY 1.021277 (500 3325);
DISPLAY INVISIBLE (500 3325);
FORCEPROP 1 LASTPIN (525 3275) $PN 1
J 0
(537 3287);
DISPLAY 0.787234 (537 3287);
PAINT MONO (537 3287);
FORCEPROP 1 LASTPIN (725 3275) $PN 2
J 0
(687 3287);
DISPLAY 0.787234 (687 3287);
PAINT MONO (687 3287);
FORCEPROP 1 LAST TOLERANCE 1%
J 0
(950 3275);
DISPLAY 0.510638 (950 3275);
FORCEPROP 1 LAST WATTAGE 1/16W
J 2
(950 3275);
DISPLAY 0.510638 (950 3275);
FORCEPROP 1 LAST VALUE 4.7K
J 2
(825 3275);
DISPLAY 0.510638 (825 3275);
FORCEPROP 1 LAST PACK_TYPE 0402LF
J 0
(1100 3275);
DISPLAY 0.510638 (1100 3275);
FORCEPROP 1 LAST MATERIAL EMPTY
J 0
(1000 3275);
DISPLAY 0.510638 (1000 3275);
PAINT RED (1000 3275);
FORCEPROP 2 LAST CDS_LIB pure_quanta
J 0
(625 3275);
DISPLAY INVISIBLE (625 3275);
FORCEPROP 1 LAST PATH I40
J 0
(575 3425);
DISPLAY 0.978723 (575 3425);
PAINT WHITE (575 3425);
DISPLAY INVISIBLE (575 3425);
FORCEPROP 1 LAST PART_NUMBER CS24702FB06
J 0
(200 3275);
DISPLAY 0.510638 (200 3275);
DISPLAY INVISIBLE (200 3275);
FORCEADD Q_RES..1
(1300 2475);
FORCEPROP 1 LAST LOCATION R3602
J 0
(1050 2475);
DISPLAY 0.638298 (1050 2475);
FORCEPROP 0 LAST $SEC 1
J 0
(1150 2575);
DISPLAY 0.680851 (1150 2575);
PAINT MONO (1150 2575);
DISPLAY INVISIBLE (1150 2575);
FORCEPROP 0 LAST CDS_SEC 1
J 0
(1150 2575);
DISPLAY 1.021277 (1150 2575);
DISPLAY INVISIBLE (1150 2575);
FORCEPROP 1 LASTPIN (1200 2475) $PN 1
J 0
(1212 2487);
DISPLAY 0.787234 (1212 2487);
PAINT MONO (1212 2487);
FORCEPROP 1 LASTPIN (1400 2475) $PN 2
J 0
(1362 2487);
DISPLAY 0.787234 (1362 2487);
PAINT MONO (1362 2487);
FORCEPROP 1 LAST WATTAGE 1/16W
J 2
(1300 2375);
DISPLAY 0.638298 (1300 2375);
FORCEPROP 1 LAST VALUE 10
J 2
(1250 2425);
DISPLAY 0.638298 (1250 2425);
FORCEPROP 1 LAST PACK_TYPE 0402LF
J 0
(1425 2425);
DISPLAY 0.638298 (1425 2425);
FORCEPROP 1 LAST MATERIAL CHIP
J 0
(1325 2375);
DISPLAY 0.638298 (1325 2375);
FORCEPROP 1 LAST TOLERANCE 1%
J 0
(1350 2425);
DISPLAY 0.638298 (1350 2425);
FORCEPROP 2 LAST CDS_LIB pure_quanta
J 0
(1300 2475);
DISPLAY INVISIBLE (1300 2475);
FORCEPROP 1 LAST PATH I41
J 0
(1250 2625);
DISPLAY 0.978723 (1250 2625);
PAINT WHITE (1250 2625);
DISPLAY INVISIBLE (1250 2625);
FORCEPROP 1 LAST PART_NUMBER CS01002FB07
J 0
(1150 2525);
DISPLAY 0.638298 (1150 2525);
DISPLAY INVISIBLE (1150 2525);
FORCEADD Q_RES..1
(1300 2200);
FORCEPROP 1 LAST LOCATION R3603
J 0
(1050 2200);
DISPLAY 0.638298 (1050 2200);
FORCEPROP 0 LAST $SEC 1
J 0
(1150 2300);
DISPLAY 0.680851 (1150 2300);
PAINT MONO (1150 2300);
DISPLAY INVISIBLE (1150 2300);
FORCEPROP 0 LAST CDS_SEC 1
J 0
(1150 2300);
DISPLAY 1.021277 (1150 2300);
DISPLAY INVISIBLE (1150 2300);
FORCEPROP 1 LASTPIN (1200 2200) $PN 1
J 0
(1212 2212);
DISPLAY 0.787234 (1212 2212);
PAINT MONO (1212 2212);
FORCEPROP 1 LASTPIN (1400 2200) $PN 2
J 0
(1362 2212);
DISPLAY 0.787234 (1362 2212);
PAINT MONO (1362 2212);
FORCEPROP 1 LAST TOLERANCE 1%
J 0
(1350 2150);
DISPLAY 0.638298 (1350 2150);
FORCEPROP 1 LAST PACK_TYPE 0402LF
J 0
(1425 2150);
DISPLAY 0.638298 (1425 2150);
FORCEPROP 1 LAST VALUE 10
J 2
(1250 2150);
DISPLAY 0.638298 (1250 2150);
FORCEPROP 1 LAST WATTAGE 1/16W
J 2
(1300 2100);
DISPLAY 0.638298 (1300 2100);
FORCEPROP 1 LAST MATERIAL CHIP
J 0
(1325 2100);
DISPLAY 0.638298 (1325 2100);
FORCEPROP 2 LAST CDS_LIB pure_quanta
J 0
(1300 2200);
DISPLAY INVISIBLE (1300 2200);
FORCEPROP 1 LAST PATH I43
J 0
(1250 2350);
DISPLAY 0.978723 (1250 2350);
PAINT WHITE (1250 2350);
DISPLAY INVISIBLE (1250 2350);
FORCEPROP 1 LAST PART_NUMBER CS01002FB07
J 0
(1150 2250);
DISPLAY 0.638298 (1150 2250);
DISPLAY INVISIBLE (1150 2250);
FORCEADD UNIVERSAL_GND..1
(200 3150);
FORCEPROP 3 LASTPIN (200 3200) SIG_NAME GND\g
J 0
(210 3210);
DISPLAY 0.659574 (210 3210);
PAINT MONO (210 3210);
DISPLAY INVISIBLE (210 3210);
FORCEPROP 2 LAST CDS_LIB pure_quanta_power
J 0
(200 3150);
DISPLAY INVISIBLE (200 3150);
FORCEPROP 1 LAST HDL_POWER GND
J 1
(225 3075);
DISPLAY 0.872340 (225 3075);
PAINT GREEN (225 3075);
DISPLAY INVISIBLE (225 3075);
FORCEPROP 1 LAST PATH I45
J 0
(275 3150);
DISPLAY 0.872340 (275 3150);
PAINT AQUA (275 3150);
DISPLAY INVISIBLE (275 3150);
FORCEADD OFFPAGE..1
(75 3075);
FORCEPROP 2 LAST $XR0 252 
J 0
(-177 3075);
DISPLAY 0.638298 (-177 3075);
PAINT MONO (-177 3075);
FORCEPROP 2 LAST CDS_LIB standard
J 0
(75 3075);
DISPLAY INVISIBLE (75 3075);
FORCEPROP 1 LAST OFFPAGE TRUE
J 0
(400 2950);
DISPLAY 0.872340 (400 2950);
DISPLAY INVISIBLE (400 2950);
FORCEPROP 1 LAST COMMENT_BODY TRUE
J 0
(200 2975);
DISPLAY 0.872340 (200 2975);
PAINT GREEN (200 2975);
DISPLAY INVISIBLE (200 2975);
FORCEPROP 2 LAST PATH I46
J 0
(125 3150);
DISPLAY 1.021277 (125 3150);
DISPLAY INVISIBLE (125 3150);
FORCEADD OFFPAGE..3
R 2
(75 3025);
FORCEPROP 2 LAST $XR0 252 
J 0
(-205 3025);
DISPLAY 0.638298 (-205 3025);
PAINT MONO (-205 3025);
FORCEPROP 2 LAST CDS_LIB standard
J 2
(75 3025);
PAINT MONO (75 3025);
DISPLAY INVISIBLE (75 3025);
FORCEPROP 1 LAST OFFPAGE TRUE
J 2
(-250 2900);
DISPLAY 0.872340 (-250 2900);
DISPLAY INVISIBLE (-250 2900);
FORCEPROP 1 LAST COMMENT_BODY TRUE
J 2
(125 2925);
DISPLAY 0.872340 (125 2925);
PAINT GREEN (125 2925);
DISPLAY INVISIBLE (125 2925);
FORCEPROP 2 LAST PATH I47
J 0
(-125 3075);
DISPLAY 1.021277 (-125 3075);
DISPLAY INVISIBLE (-125 3075);
FORCEADD UNIVERSAL_GND..1
(-500 2975);
FORCEPROP 3 LASTPIN (-500 3025) SIG_NAME GND\g
J 0
(-490 3035);
DISPLAY 0.659574 (-490 3035);
PAINT MONO (-490 3035);
DISPLAY INVISIBLE (-490 3035);
FORCEPROP 2 LAST CDS_LIB pure_quanta_power
J 0
(-500 2975);
DISPLAY INVISIBLE (-500 2975);
FORCEPROP 1 LAST HDL_POWER GND
J 1
(-475 2900);
DISPLAY 0.872340 (-475 2900);
PAINT GREEN (-475 2900);
DISPLAY INVISIBLE (-475 2900);
FORCEPROP 1 LAST PATH I49
J 0
(-425 2975);
DISPLAY 0.872340 (-425 2975);
PAINT AQUA (-425 2975);
DISPLAY INVISIBLE (-425 2975);
FORCEADD Q_CAP..1
(-500 3250);
FORCEPROP 1 LAST LOCATION C2024
J 0
(-450 3350);
DISPLAY 0.978723 (-450 3350);
FORCEPROP 0 LAST $SEC 1
J 0
(-450 3400);
DISPLAY 0.680851 (-450 3400);
PAINT MONO (-450 3400);
DISPLAY INVISIBLE (-450 3400);
FORCEPROP 0 LAST CDS_SEC 1
J 0
(-450 3400);
DISPLAY 1.021277 (-450 3400);
DISPLAY INVISIBLE (-450 3400);
FORCEPROP 1 LASTPIN (-500 3350) $PN 1
J 0
(-490 3330);
DISPLAY 0.787234 (-490 3330);
PAINT MONO (-490 3330);
FORCEPROP 1 LASTPIN (-500 3150) $PN 2
J 0
(-490 3130);
DISPLAY 0.787234 (-490 3130);
PAINT MONO (-490 3130);
FORCEPROP 1 LAST VALUE 0.1UF
J 0
(-450 3300);
DISPLAY 0.638298 (-450 3300);
FORCEPROP 1 LAST VOLTAGE 25V
J 0
(-450 3250);
DISPLAY 0.638298 (-450 3250);
FORCEPROP 1 LAST TOLERANCE 10%
J 0
(-450 3200);
DISPLAY 0.638298 (-450 3200);
FORCEPROP 1 LAST PACK_TYPE 0402
J 0
(-450 3100);
DISPLAY 0.638298 (-450 3100);
FORCEPROP 1 LAST MATERIAL X7R
J 0
(-450 3150);
DISPLAY 0.638298 (-450 3150);
FORCEPROP 2 LAST CDS_LIB pure_quanta
J 0
(-500 3250);
DISPLAY INVISIBLE (-500 3250);
FORCEPROP 1 LAST PATH I50
J 0
(-450 3400);
DISPLAY 0.978723 (-450 3400);
PAINT WHITE (-450 3400);
DISPLAY INVISIBLE (-450 3400);
FORCEPROP 1 LAST PART_NUMBER CH4104K1B00
J 0
(-450 3100);
DISPLAY 0.808511 (-450 3100);
DISPLAY INVISIBLE (-450 3100);
FORCEADD Q_CAP..1
(1650 2325);
FORCEPROP 1 LAST LOCATION C2027
J 0
(1700 2425);
DISPLAY 0.978723 (1700 2425);
FORCEPROP 0 LAST $SEC 1
J 0
(1700 2475);
DISPLAY 0.680851 (1700 2475);
PAINT MONO (1700 2475);
DISPLAY INVISIBLE (1700 2475);
FORCEPROP 0 LAST CDS_SEC 1
J 0
(1700 2475);
DISPLAY 1.021277 (1700 2475);
DISPLAY INVISIBLE (1700 2475);
FORCEPROP 1 LASTPIN (1650 2425) $PN 1
J 0
(1660 2405);
DISPLAY 0.787234 (1660 2405);
PAINT MONO (1660 2405);
FORCEPROP 1 LASTPIN (1650 2225) $PN 2
J 0
(1660 2205);
DISPLAY 0.787234 (1660 2205);
PAINT MONO (1660 2205);
FORCEPROP 1 LAST VALUE 0.1UF
J 0
(1700 2375);
DISPLAY 0.510638 (1700 2375);
FORCEPROP 1 LAST VOLTAGE 25V
J 0
(1700 2350);
DISPLAY 0.510638 (1700 2350);
FORCEPROP 1 LAST TOLERANCE 10%
J 0
(1700 2325);
DISPLAY 0.510638 (1700 2325);
FORCEPROP 1 LAST MATERIAL X7R
J 0
(1700 2300);
DISPLAY 0.510638 (1700 2300);
FORCEPROP 1 LAST PACK_TYPE 0402
J 0
(1700 2250);
DISPLAY 0.510638 (1700 2250);
FORCEPROP 2 LAST CDS_LIB pure_quanta
J 0
(1650 2325);
DISPLAY INVISIBLE (1650 2325);
FORCEPROP 1 LAST PATH I77
J 0
(1700 2475);
DISPLAY 0.978723 (1700 2475);
PAINT WHITE (1700 2475);
DISPLAY INVISIBLE (1700 2475);
FORCEPROP 1 LAST PART_NUMBER CH4104K1B00
J 0
(1700 2275);
DISPLAY 0.510638 (1700 2275);
DISPLAY INVISIBLE (1700 2275);
FORCEADD UNIVERSAL_POWER..1
(-100 2825);
FORCEPROP 3 LASTPIN (-100 2775) SIG_NAME P3V3_OCP_SFF_R\g
J 0
(-90 2785);
DISPLAY 0.659574 (-90 2785);
PAINT MONO (-90 2785);
DISPLAY INVISIBLE (-90 2785);
FORCEPROP 1 LAST HDL_POWER P3V3_OCP_SFF_R
J 1
(-100 2875);
DISPLAY 0.872340 (-100 2875);
PAINT GREEN (-100 2875);
FORCEPROP 2 LAST CDS_LIB pure_quanta_power
J 0
(-100 2825);
DISPLAY INVISIBLE (-100 2825);
FORCEPROP 1 LAST PATH I79
J 0
(-50 2850);
DISPLAY 0.872340 (-50 2850);
PAINT AQUA (-50 2850);
DISPLAY INVISIBLE (-50 2850);
FORCEADD UNIVERSAL_POWER..1
(-250 3575);
FORCEPROP 3 LASTPIN (-250 3525) SIG_NAME P3V3_OCP_SFF_R\g
J 0
(-240 3535);
DISPLAY 0.659574 (-240 3535);
PAINT MONO (-240 3535);
DISPLAY INVISIBLE (-240 3535);
FORCEPROP 1 LAST HDL_POWER P3V3_OCP_SFF_R
J 1
(-250 3625);
DISPLAY 0.872340 (-250 3625);
PAINT GREEN (-250 3625);
FORCEPROP 2 LAST CDS_LIB pure_quanta_power
J 0
(-250 3575);
DISPLAY INVISIBLE (-250 3575);
FORCEPROP 1 LAST PATH I80
J 0
(-200 3600);
DISPLAY 0.872340 (-200 3600);
PAINT AQUA (-200 3600);
DISPLAY INVISIBLE (-200 3600);
FORCEADD UNIVERSAL_POWER..1
(-1175 2825);
FORCEPROP 3 LASTPIN (-1175 2775) SIG_NAME P3V3_OCP_SFF\g
J 0
(-1165 2785);
DISPLAY 0.659574 (-1165 2785);
PAINT MONO (-1165 2785);
DISPLAY INVISIBLE (-1165 2785);
FORCEPROP 1 LAST HDL_POWER P3V3_OCP_SFF
J 1
(-1175 2875);
DISPLAY 0.872340 (-1175 2875);
PAINT GREEN (-1175 2875);
FORCEPROP 2 LAST CDS_LIB pure_quanta_power
J 0
(-1175 2825);
DISPLAY INVISIBLE (-1175 2825);
FORCEPROP 1 LAST PATH I81
J 0
(-1125 2850);
DISPLAY 0.872340 (-1125 2850);
PAINT AQUA (-1125 2850);
DISPLAY INVISIBLE (-1125 2850);
FORCEADD UNIVERSAL_POWER..1
(1825 4125);
FORCEPROP 3 LASTPIN (1825 4075) SIG_NAME P3V3_AUX\g
J 0
(1835 4085);
DISPLAY 0.659574 (1835 4085);
PAINT MONO (1835 4085);
DISPLAY INVISIBLE (1835 4085);
FORCEPROP 1 LAST HDL_POWER P3V3_AUX
J 1
(1825 4175);
DISPLAY 0.872340 (1825 4175);
PAINT GREEN (1825 4175);
FORCEPROP 2 LAST CDS_LIB pure_quanta_power
J 0
(1825 4125);
DISPLAY INVISIBLE (1825 4125);
FORCEPROP 1 LAST PATH I87
J 0
(1875 4150);
DISPLAY 0.872340 (1875 4150);
PAINT AQUA (1875 4150);
DISPLAY INVISIBLE (1875 4150);
FORCEADD Q_RES..2
(1825 3700);
FORCEPROP 1 LAST LOCATION R3628
J 0
(1870 3825);
DISPLAY 0.978723 (1870 3825);
FORCEPROP 0 LAST $SEC 1
J 0
(1875 3875);
DISPLAY 0.680851 (1875 3875);
PAINT MONO (1875 3875);
DISPLAY INVISIBLE (1875 3875);
FORCEPROP 0 LAST CDS_SEC 1
J 0
(1875 3875);
DISPLAY 1.021277 (1875 3875);
DISPLAY INVISIBLE (1875 3875);
FORCEPROP 1 LASTPIN (1825 3800) $PN 1
J 0
(1830 3762);
DISPLAY 0.787234 (1830 3762);
PAINT MONO (1830 3762);
FORCEPROP 1 LASTPIN (1825 3600) $PN 2
J 0
(1830 3610);
DISPLAY 0.787234 (1830 3610);
PAINT MONO (1830 3610);
FORCEPROP 1 LAST VALUE 4.7K
J 0
(1870 3775);
DISPLAY 0.510638 (1870 3775);
FORCEPROP 1 LAST WATTAGE 1/16W
J 0
(1865 3675);
DISPLAY 0.510638 (1865 3675);
FORCEPROP 1 LAST TOLERANCE 1%
J 0
(1870 3725);
DISPLAY 0.510638 (1870 3725);
FORCEPROP 1 LAST MATERIAL EMPTY
J 0
(1865 3625);
DISPLAY 0.510638 (1865 3625);
PAINT RED (1865 3625);
FORCEPROP 1 LAST PACK_TYPE 0402LF
J 0
(1865 3525);
DISPLAY 0.510638 (1865 3525);
FORCEPROP 2 LAST CDS_LIB pure_quanta
J 0
(1825 3700);
DISPLAY INVISIBLE (1825 3700);
FORCEPROP 1 LAST PATH I88
J 0
(1875 3875);
DISPLAY 0.978723 (1875 3875);
PAINT WHITE (1875 3875);
DISPLAY INVISIBLE (1875 3875);
FORCEPROP 1 LAST PART_NUMBER CS24702FB06
J 0
(1865 3575);
DISPLAY 0.510638 (1865 3575);
DISPLAY INVISIBLE (1865 3575);
FORCEADD Q_RES..2
(1525 3700);
FORCEPROP 1 LAST LOCATION R3627
J 0
(1570 3825);
DISPLAY 0.978723 (1570 3825);
FORCEPROP 0 LAST $SEC 1
J 0
(1575 3875);
DISPLAY 0.680851 (1575 3875);
PAINT MONO (1575 3875);
DISPLAY INVISIBLE (1575 3875);
FORCEPROP 0 LAST CDS_SEC 1
J 0
(1575 3875);
DISPLAY 1.021277 (1575 3875);
DISPLAY INVISIBLE (1575 3875);
FORCEPROP 1 LASTPIN (1525 3800) $PN 1
J 0
(1530 3762);
DISPLAY 0.787234 (1530 3762);
PAINT MONO (1530 3762);
FORCEPROP 1 LASTPIN (1525 3600) $PN 2
J 0
(1530 3610);
DISPLAY 0.787234 (1530 3610);
PAINT MONO (1530 3610);
FORCEPROP 1 LAST TOLERANCE 1%
J 0
(1570 3725);
DISPLAY 0.510638 (1570 3725);
FORCEPROP 1 LAST PACK_TYPE 0402LF
J 0
(1565 3525);
DISPLAY 0.510638 (1565 3525);
FORCEPROP 1 LAST VALUE 4.7K
J 0
(1570 3775);
DISPLAY 0.510638 (1570 3775);
FORCEPROP 1 LAST MATERIAL CHIP
J 0
(1565 3625);
DISPLAY 0.510638 (1565 3625);
FORCEPROP 1 LAST WATTAGE 1/16W
J 0
(1565 3675);
DISPLAY 0.510638 (1565 3675);
FORCEPROP 2 LAST CDS_LIB pure_quanta
J 0
(1525 3700);
DISPLAY INVISIBLE (1525 3700);
FORCEPROP 1 LAST PATH I89
J 0
(1575 3875);
DISPLAY 0.978723 (1575 3875);
PAINT WHITE (1575 3875);
DISPLAY INVISIBLE (1575 3875);
FORCEPROP 1 LAST PART_NUMBER CS24702FB06
J 0
(1565 3575);
DISPLAY 0.510638 (1565 3575);
DISPLAY INVISIBLE (1565 3575);
FORCEADD Q_RES..1
(-600 2675);
FORCEPROP 1 LAST LOCATION R3645
J 0
(-775 2675);
DISPLAY 0.638298 (-775 2675);
FORCEPROP 0 LAST $SEC 1
J 0
(-775 2725);
DISPLAY 0.680851 (-775 2725);
PAINT MONO (-775 2725);
DISPLAY INVISIBLE (-775 2725);
FORCEPROP 0 LAST CDS_SEC 1
J 0
(-775 2725);
DISPLAY 1.021277 (-775 2725);
DISPLAY INVISIBLE (-775 2725);
FORCEPROP 1 LASTPIN (-700 2675) $PN 1
J 0
(-688 2687);
DISPLAY 0.787234 (-688 2687);
PAINT MONO (-688 2687);
FORCEPROP 1 LASTPIN (-500 2675) $PN 2
J 0
(-538 2687);
DISPLAY 0.787234 (-538 2687);
PAINT MONO (-538 2687);
FORCEPROP 1 LAST WATTAGE 2W
J 2
(-625 2525);
DISPLAY 0.510638 (-625 2525);
FORCEPROP 1 LAST VALUE 0.002
J 2
(-625 2575);
DISPLAY 0.510638 (-625 2575);
FORCEPROP 1 LAST TOLERANCE 1%
J 0
(-600 2575);
DISPLAY 0.510638 (-600 2575);
FORCEPROP 1 LAST MATERIAL CHIP
J 0
(-600 2525);
DISPLAY 0.510638 (-600 2525);
FORCEPROP 1 LAST PACK_TYPE 2512LF
J 0
(-525 2575);
DISPLAY 0.510638 (-525 2575);
FORCEPROP 2 LAST CDS_LIB pure_quanta
J 0
(-600 2675);
DISPLAY INVISIBLE (-600 2675);
FORCEPROP 1 LAST PATH I93
J 0
(-650 2825);
DISPLAY 0.978723 (-650 2825);
PAINT WHITE (-650 2825);
DISPLAY INVISIBLE (-650 2825);
FORCEPROP 1 LAST PART_NUMBER CS+002AFR06
J 0
(-725 2625);
DISPLAY 0.510638 (-725 2625);
DISPLAY INVISIBLE (-725 2625);
FORCEADD QUANTA_TITLE_BLOCK_C..1
(6825 -1650);
FORCEPROP 0 LAST CDS_CON_LAST_MODIFIED Thu Sep 14 16:12:30 2023
J 0
(4940 -1635);
DISPLAY INVISIBLE (4940 -1635);
FORCEPROP 1 LAST CUSTOM_TXT_CDS <CON_LAST_MODIFIED>
J 0
(4940 -1635);
DISPLAY 0.978723 (4940 -1635);
FORCEPROP 2 LAST CUSTOM_TXT_CDS <XR_PAGE_TITLE>
J 0
(-1065 3600);
DISPLAY 0.638298 (-1065 3600);
PAINT PINK (-1065 3600);
DISPLAY INVISIBLE (-1065 3600);
FORCEPROP 1 LAST CUSTOM_TXT_CDS <NAME_2>
J 0
(3650 -1600);
FORCEPROP 1 LAST CUSTOM_TXT_CDS <NAME_1>
J 0
(3650 -1475);
FORCEPROP 1 LAST CUSTOM_TXT_CDS <Q_NUMBER>
J 0
(5422 -1547);
DISPLAY 1.212766 (5422 -1547);
FORCEPROP 1 LAST CUSTOM_TXT_CDS <Q_PROJ>
J 0
(4443 -1548);
DISPLAY 1.212766 (4443 -1548);
FORCEPROP 1 LAST CUSTOM_TXT_CDS <Q_REV>
J 0
(6641 -1547);
DISPLAY 1.212766 (6641 -1547);
FORCEPROP 1 LAST CUSTOM_TXT_CDS <CON_PAGE_NUM> OF <CON_TOTAL_PAGES>
J 0
(6379 -1632);
DISPLAY 0.978723 (6379 -1632);
FORCEPROP 1 LAST Q_TITLE POWER MONITOR (1/4)
J 0
(-2500 -1625);
DISPLAY 2.446809 (-2500 -1625);
PAINT GREEN (-2500 -1625);
FORCEPROP 2 LAST CDS_LIB pure_quanta
J 0
(6825 -1650);
DISPLAY INVISIBLE (6825 -1650);
FORCEPROP 1 LAST CDS_LMAN_SYM_OUTLINE -9475,6775,100,-125
J 0
(6825 -1650);
DISPLAY 0.468085 (6825 -1650);
PAINT GREEN (6825 -1650);
DISPLAY INVISIBLE (6825 -1650);
FORCEPROP 2 LAST PAGE_BORDER TRUE
J 0
(-1065 3600);
DISPLAY 0.638298 (-1065 3600);
PAINT PINK (-1065 3600);
DISPLAY INVISIBLE (-1065 3600);
FORCEPROP 2 LAST CDS_XR_PAGE_TITLE CR-237 : @T6G_MB_LIB.T6G(SCH_1):PAGE237
J 0
(-1065 3600);
DISPLAY 0.638298 (-1065 3600);
PAINT PINK (-1065 3600);
DISPLAY INVISIBLE (-1065 3600);
FORCEPROP 1 LAST Q_DEPT BU9
J 1
(3062 -1601);
DISPLAY 1.957447 (3062 -1601);
PAINT GREEN (3062 -1601);
DISPLAY INVISIBLE (3062 -1601);
FORCEPROP 1 LAST COMMENT_BODY TRUE
J 0
(6837 -1663);
DISPLAY 0.978723 (6837 -1663);
PAINT GREEN (6837 -1663);
DISPLAY INVISIBLE (6837 -1663);
FORCEADD DNS..2
(775 1000);
PAINT RED (775 1000);
FORCEPROP 2 LAST CDS_LIB mstr_misc
J 0
(775 1000);
DISPLAY INVISIBLE (775 1000);
FORCEPROP 1 LAST COMMENT_BODY TRUE
R 1
J 0
(850 775);
DISPLAY 0.872340 (850 775);
PAINT GREEN (850 775);
DISPLAY INVISIBLE (850 775);
FORCEADD DNS..2
(1825 3675);
PAINT RED (1825 3675);
FORCEPROP 2 LAST CDS_LIB mstr_misc
J 0
(1825 3675);
DISPLAY INVISIBLE (1825 3675);
FORCEPROP 1 LAST COMMENT_BODY TRUE
R 1
J 0
(1900 3450);
DISPLAY 0.872340 (1900 3450);
PAINT GREEN (1900 3450);
DISPLAY INVISIBLE (1900 3450);
FORCEADD BOM_NOTE..1
(-2075 4300);
FORCEPROP 0 LAST S1 POWER MONITOR WILL CHANGE TO AL000230001
J 0
(-2225 4150);
DISPLAY 1.595745 (-2225 4150);
PAINT SKYBLUE (-2225 4150);
FORCEPROP 2 LAST CDS_LIB pure_quanta_power
J 0
(-2075 4300);
DISPLAY INVISIBLE (-2075 4300);
FORCEPROP 1 LAST COMMENT_BODY TRUE
J 0
(-2050 4400);
DISPLAY 0.978723 (-2050 4400);
DISPLAY INVISIBLE (-2050 4400);
FORCEADD DNS..2
(650 3275);
PAINT RED (650 3275);
FORCEPROP 2 LAST CDS_LIB mstr_misc
J 0
(650 3275);
DISPLAY INVISIBLE (650 3275);
FORCEPROP 1 LAST COMMENT_BODY TRUE
R 1
J 0
(725 3050);
DISPLAY 0.872340 (725 3050);
PAINT GREEN (725 3050);
DISPLAY INVISIBLE (725 3050);
WIRE 16 -1 (2175 975)(2175 850);
WIRE 16 -1 (-500 550)(-500 425);
WIRE 16 -1 (4225 1275)(4225 1325);
WIRE 16 -1 (4250 3875)(4250 3925);
WIRE 16 -1 (2175 3575)(2175 3450);
WIRE 16 -1 (-500 3150)(-500 3025);
WIRE 16 -1 (4250 3675)(4250 3325);
WIRE 16 -1 (4250 3325)(4350 3325);
WIRE 16 -1 (3375 3325)(4250 3325);
FORCEPROP 2 LAST SIG_NAME OCP_SFF_P3V3_ADC_ALERT_R
J 0
(3515 3335);
DISPLAY 0.638298 (3515 3335);
PAINT WHITE (3515 3335);
FORCEPROP 2 LASTPROP $XRERR UNIQUE?
J 0
(3275 3335);
DISPLAY 0.638298 (3275 3335);
PAINT MONO (3275 3335);
DISPLAY INVISIBLE (3275 3335);
WIRE 16 -1 (4225 1075)(4225 725);
WIRE 16 -1 (4225 725)(4350 725);
WIRE 16 -1 (3375 725)(4225 725);
FORCEPROP 2 LAST SIG_NAME E1S_0_P3V3_ADC_ALERT_R
J 0
(3515 735);
DISPLAY 0.638298 (3515 735);
PAINT WHITE (3515 735);
FORCEPROP 2 LASTPROP $XRERR UNIQUE?
J 0
(3275 735);
DISPLAY 0.638298 (3275 735);
PAINT MONO (3275 735);
DISPLAY INVISIBLE (3275 735);
WIRE 16 -1 (4550 725)(5775 725);
FORCEPROP 2 LAST SIG_NAME E1S_0_P3V3_P12V_ADC_R_ALERT
J 0
(4940 735);
DISPLAY 0.638298 (4940 735);
PAINT WHITE (4940 735);
WIRE 16 -1 (2475 2925)(-250 2925);
WIRE 16 -1 (-250 3475)(-250 2925);
WIRE 16 -1 (-250 3525)(-250 3475);
WIRE 16 -1 (-500 3475)(-250 3475);
WIRE 16 -1 (-500 3350)(-500 3475);
WIRE 16 -1 (725 3350)(1825 3350);
FORCEPROP 2 LAST SIG_NAME INA230_1_A1
J 0
(1865 3360);
DISPLAY 0.638298 (1865 3360);
PAINT WHITE (1865 3360);
FORCEPROP 2 LASTPROP $XRERR UNIQUE?
J 0
(1625 3360);
DISPLAY 0.638298 (1625 3360);
PAINT MONO (1625 3360);
DISPLAY INVISIBLE (1625 3360);
WIRE 16 -1 (1825 3350)(2375 3350);
WIRE 16 -1 (1825 3600)(1825 3350);
WIRE 16 -1 (2375 3350)(2375 3225);
WIRE 16 -1 (2375 3225)(2475 3225);
WIRE 16 -1 (2250 2475)(2250 2875);
WIRE 16 -1 (2250 2475)(1650 2475);
FORCEPROP 2 LAST SIG_NAME VSENSE_P3V3_INA230_1_INP
J 0
(1665 2485);
DISPLAY 0.510638 (1665 2485);
PAINT WHITE (1665 2485);
FORCEPROP 2 LASTPROP $XRERR UNIQUE?
J 0
(1425 2485);
DISPLAY 0.638298 (1425 2485);
PAINT MONO (1425 2485);
DISPLAY INVISIBLE (1425 2485);
WIRE 16 -1 (2250 2875)(2475 2875);
WIRE 16 -1 (1650 2425)(1650 2475);
WIRE 16 -1 (1650 2475)(1400 2475);
WIRE 16 -1 (2350 2200)(2350 2825);
WIRE 16 -1 (2350 2200)(1650 2200);
FORCEPROP 2 LAST SIG_NAME VSENSE_P3V3_INA230_1_INN
J 0
(1690 2210);
DISPLAY 0.510638 (1690 2210);
PAINT WHITE (1690 2210);
FORCEPROP 2 LASTPROP $XRERR UNIQUE?
J 0
(1450 2210);
DISPLAY 0.638298 (1450 2210);
PAINT MONO (1450 2210);
DISPLAY INVISIBLE (1450 2210);
WIRE 16 -1 (2350 2825)(2475 2825);
WIRE 16 -1 (1650 2225)(1650 2200);
WIRE 16 -1 (1400 2200)(1650 2200);
WIRE 16 -1 (3375 375)(4000 375);
FORCEPROP 2 LAST SIG_NAME NC_INA230_2_NC5
J 0
(3515 385);
DISPLAY 0.638298 (3515 385);
PAINT WHITE (3515 385);
FORCEPROP 2 LASTPROP $XRERR UNIQUE?
J 0
(4030 375);
DISPLAY 0.638298 (4030 375);
PAINT MONO (4030 375);
DISPLAY INVISIBLE (4030 375);
WIRE 16 -1 (4550 3325)(5850 3325);
FORCEPROP 2 LAST SIG_NAME OCP_SFF_P3V3_P12V_ADC_R_ALERT
J 0
(4990 3335);
DISPLAY 0.638298 (4990 3335);
PAINT WHITE (4990 3335);
WIRE 16 -1 (3375 3175)(4000 3175);
FORCEPROP 2 LAST SIG_NAME NC_INA230_1_NC1
J 0
(3515 3185);
DISPLAY 0.638298 (3515 3185);
PAINT WHITE (3515 3185);
FORCEPROP 2 LASTPROP $XRERR UNIQUE?
J 0
(4030 3175);
DISPLAY 0.638298 (4030 3175);
PAINT MONO (4030 3175);
DISPLAY INVISIBLE (4030 3175);
WIRE 16 -1 (3375 3075)(4000 3075);
FORCEPROP 2 LAST SIG_NAME NC_INA230_1_NC3
J 0
(3515 3085);
DISPLAY 0.638298 (3515 3085);
PAINT WHITE (3515 3085);
FORCEPROP 2 LASTPROP $XRERR UNIQUE?
J 0
(4030 3075);
DISPLAY 0.638298 (4030 3075);
PAINT MONO (4030 3075);
DISPLAY INVISIBLE (4030 3075);
WIRE 16 -1 (3375 2975)(4000 2975);
FORCEPROP 2 LAST SIG_NAME NC_INA230_1_NC5
J 0
(3515 2985);
DISPLAY 0.638298 (3515 2985);
PAINT WHITE (3515 2985);
FORCEPROP 2 LASTPROP $XRERR UNIQUE?
J 0
(4030 2975);
DISPLAY 0.638298 (4030 2975);
PAINT MONO (4030 2975);
DISPLAY INVISIBLE (4030 2975);
WIRE 16 -1 (-500 2675)(-275 2675);
WIRE 16 -1 (-275 2675)(-100 2675);
WIRE 16 -1 (-275 2475)(-275 2675);
WIRE 16 -1 (-275 2475)(1200 2475);
WIRE 16 -1 (-100 2675)(-100 2775);
WIRE 16 -1 (-875 2675)(-700 2675);
WIRE 16 -1 (-875 2200)(-875 2675);
WIRE 16 -1 (-1175 2675)(-875 2675);
WIRE 16 -1 (-1175 2675)(-1175 2775);
WIRE 16 -1 (-875 2200)(1200 2200);
WIRE 16 -1 (-500 75)(-275 75);
WIRE 16 -1 (-275 75)(-100 75);
WIRE 16 -1 (-275 -125)(-275 75);
WIRE 16 -1 (-275 -125)(1200 -125);
WIRE 16 -1 (-100 75)(-100 175);
WIRE 16 -1 (3375 3025)(4000 3025);
FORCEPROP 2 LAST SIG_NAME NC_INA230_1_NC4
J 0
(3515 3035);
DISPLAY 0.638298 (3515 3035);
PAINT WHITE (3515 3035);
FORCEPROP 2 LASTPROP $XRERR UNIQUE?
J 0
(4030 3025);
DISPLAY 0.638298 (4030 3025);
PAINT MONO (4030 3025);
DISPLAY INVISIBLE (4030 3025);
WIRE 16 -1 (2325 3275)(2325 3175);
WIRE 16 -1 (1525 3275)(2325 3275);
FORCEPROP 2 LAST SIG_NAME INA230_1_A0
J 0
(1865 3285);
DISPLAY 0.638298 (1865 3285);
PAINT WHITE (1865 3285);
FORCEPROP 2 LASTPROP $XRERR UNIQUE?
J 0
(1625 3285);
DISPLAY 0.638298 (1625 3285);
PAINT MONO (1625 3285);
DISPLAY INVISIBLE (1625 3285);
WIRE 16 -1 (2325 3175)(2475 3175);
WIRE 16 -1 (1525 3600)(1525 3275);
WIRE 16 -1 (725 3275)(1525 3275);
WIRE 16 -1 (3375 2875)(3500 2875);
WIRE 16 -1 (3500 2875)(3500 2825);
WIRE 16 -1 (3375 2825)(3500 2825);
WIRE 16 -1 (3500 2825)(3500 2475);
WIRE 16 -1 (3375 3125)(4000 3125);
FORCEPROP 2 LAST SIG_NAME NC_INA230_1_NC2
J 0
(3515 3135);
DISPLAY 0.638298 (3515 3135);
PAINT WHITE (3515 3135);
FORCEPROP 2 LASTPROP $XRERR UNIQUE?
J 0
(4030 3125);
DISPLAY 0.638298 (4030 3125);
PAINT MONO (4030 3125);
DISPLAY INVISIBLE (4030 3125);
WIRE 16 -1 (3375 3225)(4000 3225);
FORCEPROP 2 LAST SIG_NAME NC_INA230_1_NC0
J 0
(3515 3235);
DISPLAY 0.638298 (3515 3235);
PAINT WHITE (3515 3235);
FORCEPROP 2 LASTPROP $XRERR UNIQUE?
J 0
(4030 3225);
DISPLAY 0.638298 (4030 3225);
PAINT MONO (4030 3225);
DISPLAY INVISIBLE (4030 3225);
WIRE 16 -1 (2175 3900)(2425 3900);
WIRE 16 -1 (2175 3775)(2175 3900);
WIRE 16 -1 (2425 4025)(2425 3900);
WIRE 16 -1 (2425 3900)(2425 3325);
WIRE 16 -1 (2425 3325)(2475 3325);
WIRE 16 -1 (1925 1000)(1925 575);
WIRE 16 -1 (1925 1000)(1550 1000);
WIRE 16 -1 (1925 575)(2475 575);
WIRE 16 -1 (1550 925)(1550 1000);
WIRE 16 -1 (1550 1000)(850 1000);
FORCEPROP 2 LAST SIG_NAME INA230_2_A0
J 0
(1540 1010);
DISPLAY 0.638298 (1540 1010);
PAINT WHITE (1540 1010);
FORCEPROP 2 LASTPROP $XRERR UNIQUE?
J 0
(1300 1010);
DISPLAY 0.638298 (1300 1010);
PAINT MONO (1300 1010);
DISPLAY INVISIBLE (1300 1010);
WIRE 16 -1 (3375 625)(4000 625);
FORCEPROP 2 LAST SIG_NAME NC_INA230_2_NC0
J 0
(3515 635);
DISPLAY 0.638298 (3515 635);
PAINT WHITE (3515 635);
FORCEPROP 2 LASTPROP $XRERR UNIQUE?
J 0
(4030 625);
DISPLAY 0.638298 (4030 625);
PAINT MONO (4030 625);
DISPLAY INVISIBLE (4030 625);
WIRE 16 -1 (3375 525)(4000 525);
FORCEPROP 2 LAST SIG_NAME NC_INA230_2_NC2
J 0
(3515 535);
DISPLAY 0.638298 (3515 535);
PAINT WHITE (3515 535);
FORCEPROP 2 LASTPROP $XRERR UNIQUE?
J 0
(4030 525);
DISPLAY 0.638298 (4030 525);
PAINT MONO (4030 525);
DISPLAY INVISIBLE (4030 525);
WIRE 16 -1 (3375 275)(3500 275);
WIRE 16 -1 (3500 275)(3500 225);
WIRE 16 -1 (3375 225)(3500 225);
WIRE 16 -1 (3500 225)(3500 -125);
WIRE 16 -1 (1400 -400)(1650 -400);
WIRE 16 -1 (2350 -400)(1650 -400);
FORCEPROP 2 LAST SIG_NAME VSENSE_P3V3_INA230_2_INN
J 0
(1690 -390);
DISPLAY 0.510638 (1690 -390);
PAINT WHITE (1690 -390);
FORCEPROP 2 LASTPROP $XRERR UNIQUE?
J 0
(1450 -390);
DISPLAY 0.638298 (1450 -390);
PAINT MONO (1450 -390);
DISPLAY INVISIBLE (1450 -390);
WIRE 16 -1 (1650 -375)(1650 -400);
WIRE 16 -1 (2350 -400)(2350 225);
WIRE 16 -1 (2350 225)(2475 225);
WIRE 16 -1 (2250 -125)(2250 275);
WIRE 16 -1 (2250 -125)(1650 -125);
FORCEPROP 2 LAST SIG_NAME VSENSE_P3V3_INA230_2_INP
J 0
(1665 -115);
DISPLAY 0.510638 (1665 -115);
PAINT WHITE (1665 -115);
FORCEPROP 2 LASTPROP $XRERR UNIQUE?
J 0
(1425 -115);
DISPLAY 0.638298 (1425 -115);
PAINT MONO (1425 -115);
DISPLAY INVISIBLE (1425 -115);
WIRE 16 -1 (2250 275)(2475 275);
WIRE 16 -1 (1650 -175)(1650 -125);
WIRE 16 -1 (1650 -125)(1400 -125);
WIRE 16 -1 (3375 425)(4000 425);
FORCEPROP 2 LAST SIG_NAME NC_INA230_2_NC4
J 0
(3515 435);
DISPLAY 0.638298 (3515 435);
PAINT WHITE (3515 435);
FORCEPROP 2 LASTPROP $XRERR UNIQUE?
J 0
(4030 425);
DISPLAY 0.638298 (4030 425);
PAINT MONO (4030 425);
DISPLAY INVISIBLE (4030 425);
WIRE 16 -1 (650 1075)(175 1075);
WIRE 16 -1 (175 1075)(175 1000);
WIRE 16 -1 (175 1000)(650 1000);
WIRE 16 -1 (175 925)(175 1000);
WIRE 16 -1 (-875 75)(-700 75);
WIRE 16 -1 (-1175 75)(-875 75);
WIRE 16 -1 (-875 -400)(-875 75);
WIRE 16 -1 (-875 -400)(1200 -400);
WIRE 16 -1 (-1175 75)(-1175 175);
WIRE 16 -1 (2475 325)(-250 325);
WIRE 16 -1 (-250 875)(-250 325);
WIRE 16 -1 (-250 925)(-250 875);
WIRE 16 -1 (-500 875)(-250 875);
WIRE 16 -1 (-500 750)(-500 875);
WIRE 16 -1 (200 3275)(525 3275);
WIRE 16 -1 (200 3350)(200 3275);
WIRE 16 -1 (200 3200)(200 3275);
WIRE 16 -1 (525 3350)(200 3350);
WIRE 16 -1 (1825 4075)(1825 4025);
WIRE 16 -1 (1825 4025)(1825 3800);
WIRE 16 -1 (1525 4025)(1825 4025);
WIRE 16 -1 (1525 3800)(1525 4025);
WIRE 16 -1 (1375 3075)(2475 3075);
FORCEPROP 2 LAST SIG_NAME SMB_INA230_1_3V3AUX_SCL_R1
J 0
(1690 3085);
DISPLAY 0.680851 (1690 3085);
PAINT WHITE (1690 3085);
FORCEPROP 2 LASTPROP $XRERR UNIQUE?
J 0
(1450 3085);
DISPLAY 0.638298 (1450 3085);
PAINT MONO (1450 3085);
DISPLAY INVISIBLE (1450 3085);
WIRE 16 -1 (125 475)(1175 475);
FORCEPROP 2 LAST SIG_NAME SMB_INA230_2_3V3AUX_SCL_R
J 0
(190 485);
DISPLAY 0.680851 (190 485);
PAINT WHITE (190 485);
WIRE 16 -1 (1375 425)(1550 425);
WIRE 16 -1 (1550 425)(2475 425);
FORCEPROP 2 LAST SIG_NAME SMB_INA230_2_3V3AUX_SDA_R1
J 0
(1690 435);
DISPLAY 0.680851 (1690 435);
PAINT WHITE (1690 435);
FORCEPROP 2 LASTPROP $XRERR UNIQUE?
J 0
(1450 435);
DISPLAY 0.638298 (1450 435);
PAINT MONO (1450 435);
DISPLAY INVISIBLE (1450 435);
WIRE 16 -1 (1550 725)(1550 425);
WIRE 16 -1 (1375 475)(2475 475);
FORCEPROP 2 LAST SIG_NAME SMB_INA230_2_3V3AUX_SCL_R1
J 0
(1690 485);
DISPLAY 0.680851 (1690 485);
PAINT WHITE (1690 485);
FORCEPROP 2 LASTPROP $XRERR UNIQUE?
J 0
(1450 485);
DISPLAY 0.638298 (1450 485);
PAINT MONO (1450 485);
DISPLAY INVISIBLE (1450 485);
WIRE 16 -1 (125 3025)(1175 3025);
FORCEPROP 2 LAST SIG_NAME SMB_INA230_1_3V3AUX_SDA_R
J 0
(190 3035);
DISPLAY 0.680851 (190 3035);
PAINT WHITE (190 3035);
WIRE 16 -1 (125 3075)(1175 3075);
FORCEPROP 2 LAST SIG_NAME SMB_INA230_1_3V3AUX_SCL_R
J 0
(190 3085);
DISPLAY 0.680851 (190 3085);
PAINT WHITE (190 3085);
WIRE 16 -1 (3375 475)(4000 475);
FORCEPROP 2 LAST SIG_NAME NC_INA230_2_NC3
J 0
(3515 485);
DISPLAY 0.638298 (3515 485);
PAINT WHITE (3515 485);
FORCEPROP 2 LASTPROP $XRERR UNIQUE?
J 0
(4030 475);
DISPLAY 0.638298 (4030 475);
PAINT MONO (4030 475);
DISPLAY INVISIBLE (4030 475);
WIRE 16 -1 (3375 575)(4000 575);
FORCEPROP 2 LAST SIG_NAME NC_INA230_2_NC1
J 0
(3515 585);
DISPLAY 0.638298 (3515 585);
PAINT WHITE (3515 585);
FORCEPROP 2 LASTPROP $XRERR UNIQUE?
J 0
(4030 575);
DISPLAY 0.638298 (4030 575);
PAINT MONO (4030 575);
DISPLAY INVISIBLE (4030 575);
WIRE 16 -1 (125 425)(1175 425);
FORCEPROP 2 LAST SIG_NAME SMB_INA230_2_3V3AUX_SDA_R
J 0
(190 435);
DISPLAY 0.680851 (190 435);
PAINT WHITE (190 435);
WIRE 16 -1 (2475 650)(2475 625);
WIRE 16 -1 (2050 650)(2475 650);
WIRE 16 -1 (2050 1075)(2050 650);
WIRE 16 -1 (2050 1075)(850 1075);
FORCEPROP 2 LAST SIG_NAME INA230_2_A1
J 0
(1540 1085);
DISPLAY 0.638298 (1540 1085);
PAINT WHITE (1540 1085);
FORCEPROP 2 LASTPROP $XRERR UNIQUE?
J 0
(1300 1085);
DISPLAY 0.638298 (1300 1085);
PAINT MONO (1300 1085);
DISPLAY INVISIBLE (1300 1085);
WIRE 16 -1 (2175 1300)(2425 1300);
WIRE 16 -1 (2175 1175)(2175 1300);
WIRE 16 -1 (2425 1425)(2425 1300);
WIRE 16 -1 (2425 1300)(2425 725);
WIRE 16 -1 (2425 725)(2475 725);
WIRE 16 -1 (1375 3025)(2475 3025);
FORCEPROP 2 LAST SIG_NAME SMB_INA230_1_3V3AUX_SDA_R1
J 0
(1690 3035);
DISPLAY 0.680851 (1690 3035);
PAINT WHITE (1690 3035);
FORCEPROP 2 LASTPROP $XRERR UNIQUE?
J 0
(1450 3035);
DISPLAY 0.638298 (1450 3035);
PAINT MONO (1450 3035);
DISPLAY INVISIBLE (1450 3035);
DOT 1 (4225 725);
DOT 1 (3500 2825);
DOT 1 (1825 4025);
DOT 1 (1825 3350);
DOT 1 (-875 75);
DOT 1 (-275 75);
DOT 1 (-250 875);
DOT 1 (1650 -125);
DOT 1 (1650 -400);
DOT 1 (1550 425);
DOT 1 (3500 225);
DOT 1 (175 1000);
DOT 1 (1550 1000);
DOT 1 (2425 1300);
DOT 1 (-875 2675);
DOT 1 (-275 2675);
DOT 1 (-250 3475);
DOT 1 (200 3275);
DOT 1 (1650 2200);
DOT 1 (1650 2475);
DOT 1 (1525 3275);
DOT 1 (2425 3900);
DOT 1 (4250 3325);
FORCENOTE
0X41 (7-BIT)
(4250 2475) 0;
DISPLAY LEFT (4250 2475);
DISPLAY 1.276596 (4250 2475);
PAINT WHITE (4250 2475);
FORCENOTE
ADDRESS : 0X82 (8-BIT)
(3625 2575) 0;
DISPLAY LEFT (3625 2575);
DISPLAY 1.340425 (3625 2575);
PAINT WHITE (3625 2575);
FORCENOTE
0X42 (7-BIT)
(4300 0) 0;
DISPLAY LEFT (4300 0);
DISPLAY 1.276596 (4300 0);
PAINT WHITE (4300 0);
FORCENOTE
ADDRESS : 0X84 (8-BIT)
(3650 100) 0;
DISPLAY LEFT (3650 100);
DISPLAY 1.340425 (3650 100);
PAINT WHITE (3650 100);
QUIT
